G04 ================== begin FILE IDENTIFICATION RECORD ==================*
G04 Layout Name:  15669-1.brd*
G04 Film Name:    L6*
G04 File Format:  Gerber RS274X*
G04 File Origin:  Cadence Allegro 16.5-S056*
G04 Origin Date:  Wed Nov 16 04:08:54 2016*
G04 *
G04 Layer:  VIA CLASS/L6*
G04 Layer:  PIN/L6*
G04 Layer:  ETCH/L6*
G04 Layer:  DRAWING FORMAT/LAYER_PCB_STORY*
G04 Layer:  DRAWING FORMAT/LAYER_L6*
G04 *
G04 Offset:    (0.00 0.00)*
G04 Mirror:    No*
G04 Mode:      Positive*
G04 Rotation:  0*
G04 FullContactRelief:  No*
G04 UndefLineWidth:     6.00*
G04 ================== end FILE IDENTIFICATION RECORD ====================*
%FSLAX35Y35*MOIN*%
%IR0*IPPOS*OFA0.00000B0.00000*MIA0B0*SFA1.00000B1.00000*%
%ADD10C,.02*%
%ADD11C,.022*%
%ADD12C,.028*%
%ADD13C,.01*%
%ADD14C,.04*%
%ADD15C,.006*%
%ADD16C,.0065*%
%ADD18C,.04404*%
%ADD19C,.04604*%
%ADD17C,.11104*%
G75*
%LPD*%
G75*
G36*
G01X3937Y3004D02*
G02X3004Y3937I0J933D01*
G01Y596998D01*
X13760D01*
Y733776D01*
X16929D01*
G03Y749232I0J7728D01*
G01X13760D01*
Y924002D01*
X3004D01*
Y1092998D01*
X13760D01*
Y1229839D01*
X16929D01*
G03Y1245295I0J7728D01*
G01X13760D01*
Y1420002D01*
X3004D01*
Y1510498D01*
X13760D01*
Y1647161D01*
X16929D01*
G03Y1662618I0J7728D01*
G01X13760D01*
Y1817708D01*
X14052Y1818000D01*
X25970D01*
X29558Y1814412D01*
X38887D01*
X40227Y1813072D01*
Y1806746D01*
X39736Y1803962D01*
X18000Y1782226D01*
Y1754341D01*
X17999Y1754331D01*
G03X17988Y1754127I2001J-210D01*
G01Y1750926D01*
G03X17999Y1750721I2012J5D01*
G01X18000Y1750711D01*
Y1741743D01*
X17999Y1741733D01*
G03X17988Y1741529I2001J-210D01*
G01Y1738328D01*
G03X17999Y1738123I2012J5D01*
G01X18000Y1738113D01*
Y1729144D01*
X17999Y1729134D01*
G03X17988Y1728930I2001J-210D01*
G01Y1725729D01*
G03X17999Y1725524I2012J5D01*
G01X18000Y1725514D01*
Y1716546D01*
X17999Y1716536D01*
G03X17988Y1716332I2001J-210D01*
G01Y1713131D01*
G03X17999Y1712926I2012J5D01*
G01X18000Y1712916D01*
Y1694498D01*
X17999Y1694488D01*
G03X17988Y1694283I2001J-210D01*
G01Y1691083D01*
G03X17999Y1690878I2012J5D01*
G01X18000Y1690868D01*
Y1681900D01*
X17999Y1681890D01*
G03X17988Y1681685I2001J-210D01*
G01Y1678485D01*
G03X17999Y1678280I2012J5D01*
G01X18000Y1678270D01*
Y1669302D01*
X17999Y1669292D01*
G03X17988Y1669087I2001J-210D01*
G01Y1665887D01*
G03X22004Y1665713I2012J0D01*
G01X22012Y1665800D01*
Y1665928D01*
G02X22589Y1666286I400J0D01*
G02Y1643493I-5660J-11397D01*
G02X22012Y1643851I-177J358D01*
G01Y1643900D01*
G03X17988Y1643890I-2012J-10D01*
G01Y1640690D01*
G03X17999Y1640485I2012J5D01*
G01X18000Y1640475D01*
Y1631506D01*
X17999Y1631496D01*
G03X17988Y1631292I2001J-210D01*
G01Y1628091D01*
G03X17999Y1627886I2012J5D01*
G01X18000Y1627876D01*
Y1618908D01*
X17999Y1618898D01*
G03X17988Y1618694I2001J-210D01*
G01Y1615493D01*
G03X17999Y1615288I2012J5D01*
G01X18000Y1615278D01*
Y1606309D01*
X17999Y1606299D01*
G03X17988Y1606095I2001J-210D01*
G01Y1602894D01*
G03X17999Y1602689I2012J5D01*
G01X18000Y1602679D01*
Y1593711D01*
X17999Y1593701D01*
G03X17988Y1593497I2001J-210D01*
G01Y1590296D01*
G03X17999Y1590091I2012J5D01*
G01X18000Y1590081D01*
Y1571664D01*
X17999Y1571654D01*
G03X17988Y1571449I2001J-210D01*
G01Y1568249D01*
G03X17999Y1568044I2012J5D01*
G01X18000Y1568034D01*
Y1559065D01*
X17999Y1559055D01*
G03X17988Y1558850I2001J-210D01*
G01Y1555650D01*
G03X17999Y1555445I2012J5D01*
G01X18000Y1555435D01*
Y1546467D01*
X17999Y1546457D01*
G03X17988Y1546252I2001J-210D01*
G01Y1543052D01*
G03X17999Y1542847I2012J5D01*
G01X18000Y1542837D01*
Y1533869D01*
X17999Y1533859D01*
G03X17988Y1533654I2001J-210D01*
G01Y1530454D01*
G03X17999Y1530249I2012J5D01*
G01X18000Y1530239D01*
Y1412610D01*
X17999Y1412600D01*
G03X17988Y1412395I2001J-210D01*
G01Y1409195D01*
G03X17999Y1408990I2012J5D01*
G01X18000Y1408980D01*
Y1400011D01*
X17999Y1400001D01*
G03X17988Y1399796I2001J-210D01*
G01Y1396596D01*
G03X17999Y1396391I2012J5D01*
G01X18000Y1396381D01*
Y1387413D01*
X17999Y1387403D01*
G03X17988Y1387198I2001J-210D01*
G01Y1383998D01*
G03X17999Y1383793I2012J5D01*
G01X18000Y1383783D01*
Y1374814D01*
X17999Y1374804D01*
G03X17988Y1374599I2001J-210D01*
G01Y1371399D01*
G03X17999Y1371194I2012J5D01*
G01X18000Y1371184D01*
Y1362216D01*
X17999Y1362206D01*
G03X17988Y1362001I2001J-210D01*
G01Y1358801D01*
G03X17999Y1358596I2012J5D01*
G01X18000Y1358586D01*
Y1349617D01*
X17999Y1349607D01*
G03X17988Y1349402I2001J-210D01*
G01Y1346202D01*
G03X17999Y1345997I2012J5D01*
G01X18000Y1345987D01*
Y1337019D01*
X17999Y1337009D01*
G03X17988Y1336804I2001J-210D01*
G01Y1333604D01*
G03X17999Y1333399I2012J5D01*
G01X18000Y1333389D01*
Y1324421D01*
X17999Y1324411D01*
G03X17988Y1324206I2001J-210D01*
G01Y1321006D01*
G03X17999Y1320801I2012J5D01*
G01X18000Y1320791D01*
Y1302373D01*
X17999Y1302363D01*
G03X17988Y1302158I2001J-210D01*
G01Y1298958D01*
G03X17999Y1298753I2012J5D01*
G01X18000Y1298743D01*
Y1289775D01*
X17999Y1289765D01*
G03X17988Y1289560I2001J-210D01*
G01Y1286360D01*
G03X17999Y1286155I2012J5D01*
G01X18000Y1286145D01*
Y1277176D01*
X17999Y1277166D01*
G03X17988Y1276961I2001J-210D01*
G01Y1273761D01*
G03X17999Y1273556I2012J5D01*
G01X18000Y1273546D01*
Y1264578D01*
X17999Y1264568D01*
G03X17988Y1264363I2001J-210D01*
G01Y1261163D01*
G03X17999Y1260958I2012J5D01*
G01X18000Y1260948D01*
Y1251980D01*
X17999Y1251970D01*
G03X17988Y1251765I2001J-210D01*
G01Y1248565D01*
G03X22004Y1248391I2012J0D01*
G01X22012Y1248478D01*
Y1248605D01*
G02X22589Y1248963I400J0D01*
G02X18000Y1224888I-5659J-11396D01*
G01Y1220484D01*
X17999Y1220474D01*
G03X17988Y1220269I2001J-210D01*
G01Y1217069D01*
G03X17999Y1216864I2012J5D01*
G01X18000Y1216854D01*
Y1207885D01*
X17999Y1207875D01*
G03X17988Y1207670I2001J-210D01*
G01Y1204470D01*
G03X17999Y1204265I2012J5D01*
G01X18000Y1204255D01*
Y1195287D01*
X17999Y1195277D01*
G03X17988Y1195072I2001J-210D01*
G01Y1191872D01*
G03X17999Y1191667I2012J5D01*
G01X18000Y1191657D01*
Y1182688D01*
X17999Y1182678D01*
G03X17988Y1182473I2001J-210D01*
G01Y1179273D01*
G03X17999Y1179068I2012J5D01*
G01X18000Y1179058D01*
Y1170090D01*
X17999Y1170080D01*
G03X17988Y1169875I2001J-210D01*
G01Y1166675D01*
G03X17999Y1166470I2012J5D01*
G01X18000Y1166460D01*
Y1157491D01*
X17999Y1157481D01*
G03X17988Y1157276I2001J-210D01*
G01Y1154076D01*
G03X17999Y1153871I2012J5D01*
G01X18000Y1153861D01*
Y1144893D01*
X17999Y1144883D01*
G03X17988Y1144678I2001J-210D01*
G01Y1141478D01*
G03X17999Y1141273I2012J5D01*
G01X18000Y1141263D01*
Y1119696D01*
X17999Y1119686D01*
G03X17988Y1119481I2001J-210D01*
G01Y1116281D01*
G03X17999Y1116076I2012J5D01*
G01X18000Y1116066D01*
Y1107098D01*
X17999Y1107088D01*
G03X17988Y1106883I2001J-210D01*
G01Y1103683D01*
G03X17999Y1103478I2012J5D01*
G01X18000Y1103468D01*
Y1088500D01*
X8000Y1078500D01*
Y1071526D01*
G03Y1063452I3811J-4037D01*
G01Y1046623D01*
X6498Y1045122D01*
Y1004378D01*
X8000Y1002877D01*
Y953415D01*
G03Y945341I3811J-4037D01*
G01Y934000D01*
X18000Y924000D01*
Y916547D01*
X17999Y916537D01*
G03X17988Y916332I2001J-210D01*
G01Y913132D01*
G03X17999Y912927I2012J5D01*
G01X18000Y912917D01*
Y903948D01*
X17999Y903938D01*
G03X17988Y903733I2001J-210D01*
G01Y900533D01*
G03X17999Y900328I2012J5D01*
G01X18000Y900318D01*
Y878751D01*
X17999Y878741D01*
G03X17988Y878536I2001J-210D01*
G01Y875336D01*
G03X17999Y875131I2012J5D01*
G01X18000Y875121D01*
Y866153D01*
X17999Y866143D01*
G03X17988Y865938I2001J-210D01*
G01Y862738D01*
G03X17999Y862533I2012J5D01*
G01X18000Y862523D01*
Y853554D01*
X17999Y853544D01*
G03X17988Y853339I2001J-210D01*
G01Y850139D01*
G03X17999Y849934I2012J5D01*
G01X18000Y849924D01*
Y840956D01*
X17999Y840946D01*
G03X17988Y840741I2001J-210D01*
G01Y837541D01*
G03X17999Y837336I2012J5D01*
G01X18000Y837326D01*
Y828358D01*
X17999Y828348D01*
G03X17988Y828143I2001J-210D01*
G01Y824943D01*
G03X17999Y824738I2012J5D01*
G01X18000Y824728D01*
Y815759D01*
X17999Y815749D01*
G03X17988Y815544I2001J-210D01*
G01Y812344D01*
G03X17999Y812139I2012J5D01*
G01X18000Y812129D01*
Y803161D01*
X17999Y803151D01*
G03X17988Y802946I2001J-210D01*
G01Y799746D01*
G03X17999Y799541I2012J5D01*
G01X18000Y799531D01*
Y790562D01*
X17999Y790552D01*
G03X17988Y790347I2001J-210D01*
G01Y787147D01*
G03X17999Y786942I2012J5D01*
G01X18000Y786932D01*
Y768515D01*
X17999Y768505D01*
G03X17988Y768300I2001J-210D01*
G01Y765100D01*
G03X17999Y764895I2012J5D01*
G01X18000Y764885D01*
Y755917D01*
X17999Y755907D01*
G03X17988Y755702I2001J-210D01*
G01Y752502D01*
G03X22004Y752328I2012J0D01*
G01X22012Y752415D01*
Y752542D01*
G02X22589Y752900I400J0D01*
G02X29518Y739655I-5660J-11396D01*
G02X28904Y739378I-396J58D01*
G03X27419Y735351I-1205J-1843D01*
G02X27707Y734742I-51J-397D01*
G02X19439Y729030I-10778J6762D01*
G01X18000D01*
Y724421D01*
X17999Y724411D01*
G03X17988Y724206I2001J-210D01*
G01Y721006D01*
G03X17999Y720801I2012J5D01*
G01X18000Y720791D01*
Y711822D01*
X17999Y711812D01*
G03X17988Y711607I2001J-210D01*
G01Y708407D01*
G03X17999Y708202I2012J5D01*
G01X18000Y708192D01*
Y699224D01*
X17999Y699214D01*
G03X17988Y699009I2001J-210D01*
G01Y695809D01*
G03X17999Y695604I2012J5D01*
G01X18000Y695594D01*
Y686625D01*
X17999Y686615D01*
G03X17988Y686410I2001J-210D01*
G01Y683210D01*
G03X17999Y683005I2012J5D01*
G01X18000Y682995D01*
Y674027D01*
X17999Y674017D01*
G03X17988Y673812I2001J-210D01*
G01Y670612D01*
G03X17999Y670407I2012J5D01*
G01X18000Y670397D01*
Y661428D01*
X17999Y661418D01*
G03X17988Y661213I2001J-210D01*
G01Y658013D01*
G03X17999Y657808I2012J5D01*
G01X18000Y657798D01*
Y648830D01*
X17999Y648820D01*
G03X17988Y648615I2001J-210D01*
G01Y645415D01*
G03X17999Y645210I2012J5D01*
G01X18000Y645200D01*
Y636232D01*
X17999Y636222D01*
G03X17988Y636017I2001J-210D01*
G01Y632817D01*
G03X17999Y632612I2012J5D01*
G01X18000Y632602D01*
Y623633D01*
X17999Y623623D01*
G03X17988Y623418I2001J-210D01*
G01Y620218D01*
G03X17999Y620013I2012J5D01*
G01X18000Y620003D01*
Y611035D01*
X17999Y611025D01*
G03X17988Y610820I2001J-210D01*
G01Y607620D01*
G03X17999Y607415I2012J5D01*
G01X18000Y607405D01*
Y588500D01*
X8000Y578500D01*
Y575463D01*
G03Y567389I3811J-4037D01*
G01Y8000D01*
X119262D01*
Y3004D01*
X3937D01*
G37*
G36*
G01X17000Y1822300D02*
X13809Y1825491D01*
Y1838197D01*
X13414Y1838592D01*
X7131D01*
X6898Y1838825D01*
Y1855814D01*
X7482Y1856399D01*
X14124D01*
X17465Y1859740D01*
Y1865153D01*
X14144Y1868474D01*
X9962D01*
X9217Y1869219D01*
Y1877217D01*
X12938Y1880938D01*
X32027D01*
X32100Y1880865D01*
Y1822755D01*
X31645Y1822300D01*
X17000D01*
G37*
G36*
G01X1020094Y1686309D02*
G03X1029402Y1700056I3134J7903D01*
G01Y1984126D01*
X8000D01*
Y1881771D01*
X5866Y1879638D01*
X3004D01*
Y1988189D01*
G02X3937Y1989122I933J0D01*
G01X1033465D01*
G02X1034398Y1988189I0J-933D01*
G01Y1686599D01*
X1032220Y1684421D01*
X1028700D01*
X1028690Y1684422D01*
G03X1020223Y1675955I-773J-7694D01*
G01X1020224Y1675945D01*
Y1621265D01*
X1018046Y1619087D01*
X993681D01*
G03Y1608866I0J-5110D01*
G01X1018046D01*
X1020224Y1606688D01*
Y1434291D01*
X1020223Y1434280D01*
G03X1028689Y1425814I7607J-859D01*
G01X1028700Y1425815D01*
X1032220D01*
X1034398Y1423637D01*
Y729030D01*
X1029402D01*
Y1410180D01*
G03X1020094Y1423927I-6174J5844D01*
G02X1015228Y1434291I8606J10365D01*
G01Y1603870D01*
X993681D01*
G02Y1624083I0J10106D01*
G01X1015228D01*
Y1675945D01*
G02X1020094Y1686309I13472J-1D01*
G37*
G36*
G01X148780Y3004D02*
Y8000D01*
X1029402D01*
Y728530D01*
X1034398D01*
Y3937D01*
G02X1033465Y3004I-933J0D01*
G01X148780D01*
G37*
G36*
G01X410500Y422709D02*
X410321Y422690D01*
G03Y418310I229J-2190D01*
G01X410500Y418291D01*
Y390000D01*
X390000Y369500D01*
X377424D01*
G02X377082Y370107I0J400D01*
G03X373318I-1882J1143D01*
G02X372976Y369500I-342J-207D01*
G01X321500D01*
X310000Y381000D01*
Y428500D01*
X324500Y443000D01*
X348523D01*
G03X351959I1718J1377D01*
G01X384094D01*
G03X387698I1802J1265D01*
G01X391000D01*
X410500Y423500D01*
Y422709D01*
G37*
G36*
G01Y820000D02*
X397694Y807194D01*
G02X397041Y807327I-282J283D01*
G03X394173Y804459I-2041J-827D01*
G02X394306Y803806I-150J-371D01*
G01X390000Y799500D01*
X321500D01*
X310000Y811000D01*
Y858500D01*
X324500Y873000D01*
X341970D01*
G03X345528I1779J1298D01*
G01X377434D01*
G03X381022I1794J1277D01*
G01X391000D01*
X410500Y853500D01*
Y852709D01*
X410321Y852690D01*
G03Y848310I229J-2190D01*
G01X410500Y848291D01*
Y820000D01*
G37*
G36*
G01X321500Y1171000D02*
X310000Y1182500D01*
Y1230000D01*
X324500Y1244500D01*
X341915D01*
G03X345583I1834J1219D01*
G01X377459D01*
G03X381039I1790J1282D01*
G01X391000D01*
X398573Y1236927D01*
X398588Y1236878D01*
G03X400078Y1235388I2112J622D01*
G01X400127Y1235373D01*
X410500Y1225000D01*
Y1191500D01*
X399610Y1180610D01*
G02X398931Y1180948I-283J283D01*
G03X397052Y1179069I-2181J302D01*
G02X397390Y1178390I55J-396D01*
G01X397228Y1178228D01*
X397121Y1178251D01*
G03X394386Y1175516I-484J-2251D01*
G01X394409Y1175409D01*
X390000Y1171000D01*
X321500D01*
G37*
G36*
G01X333202Y1735595D02*
X336995Y1739389D01*
X394611D01*
X410500Y1723500D01*
Y1690000D01*
X390000Y1669500D01*
X321500D01*
X310000Y1681000D01*
Y1728500D01*
X320889Y1739389D01*
X331217D01*
G02X331500Y1738706I0J-400D01*
G01X329798Y1737005D01*
Y1709898D01*
G03X333202I1702J-1398D01*
G01Y1735595D01*
G37*
G36*
G01X1011098Y1509646D02*
Y1426599D01*
X1007599Y1423100D01*
X998900D01*
X998300Y1422500D01*
X934500D01*
X933423Y1423577D01*
Y1509352D01*
X934271Y1510200D01*
X1010544D01*
X1011098Y1509646D01*
G37*
G36*
G01X933418Y1515433D02*
Y1605525D01*
X934382Y1606489D01*
X980451D01*
X988690Y1598250D01*
X1010129D01*
X1011156Y1597223D01*
Y1515058D01*
X1010498Y1514400D01*
X934451D01*
X933418Y1515433D01*
G37*
%LPC*%
G75*
G36*
G01X367962Y438135D02*
G03X368254Y438615I-97J388D01*
G02X372522Y438544I2143J507D01*
G03X372768Y438064I386J-105D01*
G02X370519Y434370I-768J-2064D01*
G03X369981I-269J-296D01*
G02X367962Y438135I-1481J1630D01*
G37*
G36*
G01X398630Y382269D02*
G03Y381731I296J-269D01*
G02X395370I-1630J-1481D01*
G03Y382269I-296J269D01*
G02X398630I1630J1481D01*
G37*
G36*
G01X370519Y863370D02*
G03X369981I-269J-296D01*
G02Y866630I-1481J1630D01*
G03X370519I269J296D01*
G02Y863370I1481J-1630D01*
G37*
G36*
G01X401945Y841290D02*
G03X401637Y841828I-373J143D01*
G02X404055Y843210I363J2172D01*
G03X404363Y842672I373J-143D01*
G02X401945Y841290I-363J-2172D01*
G37*
G36*
G01X327670Y813293D02*
G03Y812708I273J-292D01*
G02X324664I-1503J-1609D01*
G03Y813293I-273J293D01*
G02X327670I1503J1609D01*
G37*
G36*
G01X367824Y1238596D02*
G03X368085Y1239087I-123J380D01*
G02X372322Y1239111I2115J613D01*
G03X372598Y1238619I385J-107D01*
G02X370519Y1234870I-598J-2119D01*
G03X369981I-269J-296D01*
G02X367824Y1238596I-1481J1630D01*
G37*
G36*
G01X381412Y1734774D02*
G03X380797Y1734728I-288J-277D01*
G02X380588Y1737526I-1797J1273D01*
G03X381203Y1737572I288J277D01*
G02X381412Y1734774I1797J-1273D01*
G37*
G36*
G01X367521Y1732869D02*
G03X366967Y1732853I-269J-296D01*
G02X366879Y1736031I-1567J1547D01*
G03X367433Y1736047I269J296D01*
G02X370481Y1736130I1567J-1547D01*
G03X371019I269J296D01*
G02Y1732870I1481J-1630D01*
G03X370481I-269J-296D01*
G02X367521Y1732869I-1481J1630D01*
G37*
G36*
G01X377815Y1728364D02*
G03X378322Y1728095I384J111D01*
G02X376885Y1725386I678J-2095D01*
G03X376378Y1725655I-384J-111D01*
G02X377815Y1728364I-678J2095D01*
G37*
G36*
G01X387269Y1671370D02*
G03X386731I-269J-296D01*
G02Y1674630I-1481J1630D01*
G03X387269I269J296D01*
G02Y1671370I1481J-1630D01*
G37*
G54D18*
X318656Y391440D03*
X326156D03*
X337500Y406250D03*
X331500Y393000D03*
X339500Y416750D03*
X313500Y386000D03*
X327500Y373000D03*
X321500Y413000D03*
X331300Y408500D03*
X370000Y411000D03*
Y405500D03*
X375500D03*
X381000D03*
X375500Y411000D03*
X381000D03*
X359000D03*
X364500D03*
Y405500D03*
X359000D03*
X370000Y400000D03*
X381000D03*
X375500D03*
X370000Y389000D03*
Y394500D03*
X375500D03*
Y389000D03*
X381000D03*
Y394500D03*
X364500Y400000D03*
X365000Y394500D03*
Y389000D03*
X359000D03*
Y394500D03*
Y400000D03*
X397000Y414750D03*
X401500Y401500D03*
Y410250D03*
X375200Y429250D03*
X321500Y807000D03*
X339500Y846750D03*
X337500Y836250D03*
X331500Y823000D03*
X321500Y843000D03*
X323000Y819500D03*
X327500Y803000D03*
X331300Y838500D03*
X370000Y841000D03*
Y835500D03*
X375500D03*
X381000D03*
X375500Y841000D03*
X381000D03*
X359000D03*
X364500D03*
Y835500D03*
X359000D03*
X370000Y830000D03*
X381000D03*
X375500D03*
X370000Y819000D03*
Y824500D03*
X375500D03*
Y819000D03*
X381000D03*
Y824500D03*
X364500Y830000D03*
X365000Y824500D03*
Y819000D03*
X359000D03*
Y824500D03*
Y830000D03*
X397000Y844750D03*
X401500Y836000D03*
X368700Y803750D03*
X375200Y858250D03*
X388250Y803300D03*
X360100Y808080D03*
X337500Y1207750D03*
X339500Y1218250D03*
X331500Y1194500D03*
X321500Y1214500D03*
X313500Y1187500D03*
X327500Y1174500D03*
X331300Y1210000D03*
X370000Y1212500D03*
Y1207000D03*
X375500D03*
X381000D03*
X375500Y1212500D03*
X381000D03*
X359000D03*
X364500D03*
Y1207000D03*
X359000D03*
X370000Y1201500D03*
X381000D03*
X375500D03*
X370000Y1190500D03*
Y1196000D03*
X375500D03*
Y1190500D03*
X381000D03*
Y1196000D03*
X364500Y1201500D03*
X365000Y1196000D03*
Y1190500D03*
X359000D03*
Y1196000D03*
Y1201500D03*
X402000Y1202500D03*
X391500Y1218500D03*
X405500Y1192000D03*
X375200Y1229750D03*
X374200Y1174750D03*
X398750Y1188250D03*
X359175Y1179640D03*
X318156Y1692440D03*
X325656D03*
X339500Y1716750D03*
X337500Y1706250D03*
X331500Y1695000D03*
X321500Y1713000D03*
X327500Y1673000D03*
X359000Y1705500D03*
Y1700000D03*
Y1694500D03*
Y1689000D03*
X365000D03*
Y1694500D03*
X364500Y1700000D03*
Y1705500D03*
Y1711000D03*
X359000D03*
X381000D03*
X375500D03*
X381000Y1705500D03*
X375500D03*
X381000Y1694500D03*
Y1689000D03*
X375500D03*
Y1694500D03*
X370000D03*
Y1689000D03*
Y1705500D03*
Y1711000D03*
X381000Y1700000D03*
X375500D03*
X370000D03*
X402000Y1701000D03*
X393000Y1723500D03*
X383000Y1728700D03*
X395500Y1690500D03*
X376890Y1678000D03*
G54D19*
X393500Y422000D03*
Y852000D03*
X317156Y1193440D03*
X324656D03*
X379500Y1673750D03*
G54D17*
X11811Y1484811D03*
Y1445441D03*
%LPD*%
G75*
G54D10*
G01X-106883Y-224955D02*
Y-304955D01*
G01Y-260455D02*
X1019417D01*
G01X-106883Y-304955D02*
X1019417D01*
G01X-110883Y-208955D02*
G02I-12000J0D01*
G01X-116033D02*
G02I-6850J0D01*
G01X-122883Y-224955D02*
Y-192955D01*
G01X-106883Y-208955D02*
X-138883D01*
G01X-106883Y-224955D02*
X1019417D01*
G01X231917D02*
Y-304955D01*
G01X369417Y-224955D02*
Y-304955D01*
G01X484417Y-224955D02*
Y-304955D01*
G01X651917Y-224955D02*
Y-304955D01*
G01X821917Y-224955D02*
Y-304955D01*
G01X1019417Y-224955D02*
Y-304955D01*
G01X1047417Y-208955D02*
G02I-12000J0D01*
G01X1042267D02*
G02I-6850J0D01*
G01X1035417Y-224955D02*
Y-192955D01*
G01X1051417Y-208955D02*
X1019417D01*
X5500Y40982D03*
Y20982D03*
X10018Y5500D03*
X30018D03*
X5500Y120982D03*
Y100982D03*
Y80982D03*
Y60982D03*
Y180982D03*
Y160982D03*
Y140982D03*
Y260982D03*
Y240982D03*
Y220982D03*
Y200982D03*
Y320982D03*
Y300982D03*
Y280982D03*
Y400982D03*
Y380982D03*
Y360982D03*
Y340982D03*
Y480982D03*
Y460982D03*
Y440982D03*
Y420982D03*
Y540982D03*
Y520982D03*
Y500982D03*
X16500Y624765D03*
Y618765D03*
Y612166D03*
Y606166D03*
Y598197D03*
X27529Y601522D03*
Y604722D03*
Y614071D03*
Y617271D03*
Y626719D03*
Y629919D03*
X16500Y700355D03*
Y694355D03*
Y687757D03*
Y681757D03*
Y675158D03*
Y669158D03*
Y662226D03*
Y657000D03*
Y649500D03*
Y644530D03*
Y637363D03*
Y631363D03*
X27529Y664515D03*
Y667715D03*
Y677113D03*
Y680313D03*
Y689711D03*
Y692911D03*
Y702310D03*
Y639318D03*
Y642518D03*
X24500Y732329D03*
X16500Y769646D03*
Y763646D03*
Y757048D03*
Y725552D03*
Y719552D03*
Y712953D03*
Y706953D03*
Y751658D03*
Y732500D03*
X27529Y714708D03*
Y717908D03*
Y727307D03*
Y730507D03*
Y758803D03*
Y762003D03*
Y705510D03*
Y771401D03*
Y774601D03*
X16500Y848686D03*
Y842087D03*
Y836087D03*
Y829489D03*
Y823489D03*
Y816891D03*
Y810891D03*
Y804292D03*
Y798292D03*
Y791694D03*
Y785694D03*
Y777725D03*
X27529Y843642D03*
Y846842D03*
Y793448D03*
Y796648D03*
Y806047D03*
Y809247D03*
Y818645D03*
Y821845D03*
Y831244D03*
Y834444D03*
X16500Y917678D03*
Y911678D03*
Y905079D03*
Y899079D03*
Y879883D03*
Y873883D03*
Y867284D03*
Y861284D03*
Y854686D03*
Y889500D03*
X27529Y894236D03*
Y897436D03*
Y856241D03*
Y859441D03*
Y906834D03*
Y910034D03*
Y868839D03*
Y872039D03*
Y881487D03*
Y884687D03*
X5500Y980299D03*
X30000Y991000D03*
X5500Y1040299D03*
Y1020299D03*
Y1000299D03*
X23291Y1062791D03*
X16500Y1140024D03*
Y1120828D03*
Y1114828D03*
Y1108229D03*
Y1102229D03*
Y1133500D03*
Y1094260D03*
X27529Y1135181D03*
Y1138381D03*
Y1097585D03*
Y1100785D03*
Y1110184D03*
Y1113384D03*
X16500Y1209016D03*
Y1203016D03*
Y1196418D03*
Y1190418D03*
Y1183820D03*
Y1177820D03*
Y1171221D03*
Y1165221D03*
Y1158623D03*
Y1152623D03*
Y1146024D03*
X27529Y1185574D03*
Y1188774D03*
Y1147779D03*
Y1150979D03*
Y1198173D03*
Y1201373D03*
Y1160378D03*
Y1163578D03*
Y1210771D03*
Y1172976D03*
Y1176176D03*
X24500Y1228386D03*
X16500Y1284906D03*
Y1278308D03*
Y1272308D03*
Y1265709D03*
Y1259709D03*
Y1253111D03*
Y1247721D03*
Y1221615D03*
Y1215615D03*
Y1228500D03*
X27529Y1254866D03*
Y1258066D03*
Y1267464D03*
Y1270664D03*
Y1280063D03*
Y1283263D03*
Y1213971D03*
Y1223370D03*
Y1226570D03*
X16500Y1357347D03*
Y1350749D03*
Y1344749D03*
Y1338150D03*
Y1332150D03*
Y1325552D03*
Y1319552D03*
Y1303505D03*
Y1297505D03*
Y1290906D03*
X16417Y1311583D03*
X27529Y1314908D03*
Y1318108D03*
Y1327507D03*
Y1330707D03*
Y1340105D03*
Y1343305D03*
Y1352704D03*
Y1355904D03*
Y1292661D03*
Y1295861D03*
X36170Y1308434D03*
X26500Y1305121D03*
X33938Y1311000D03*
X38500D03*
X30000Y1305000D03*
X30700Y1308600D03*
X16500Y1413741D03*
Y1407741D03*
Y1401142D03*
Y1395142D03*
Y1388544D03*
Y1382544D03*
Y1375946D03*
Y1369946D03*
Y1363347D03*
X27529Y1365102D03*
Y1368302D03*
Y1377700D03*
Y1380900D03*
Y1390299D03*
Y1393499D03*
Y1402897D03*
Y1406097D03*
X28000Y1444000D03*
X16500Y1573000D03*
Y1566500D03*
Y1560500D03*
Y1554000D03*
Y1548000D03*
Y1541500D03*
Y1535000D03*
Y1529000D03*
Y1521031D03*
Y1512500D03*
X27529Y1524156D03*
Y1527356D03*
Y1536755D03*
Y1539955D03*
Y1549353D03*
Y1552553D03*
Y1561952D03*
Y1565152D03*
X16500Y1644735D03*
Y1639845D03*
Y1633000D03*
Y1626500D03*
Y1620000D03*
Y1614000D03*
Y1607500D03*
Y1601500D03*
Y1595000D03*
Y1588500D03*
Y1582500D03*
X27529Y1634393D03*
Y1637593D03*
Y1587199D03*
Y1583999D03*
Y1599797D03*
Y1596597D03*
Y1612396D03*
Y1609196D03*
Y1624994D03*
Y1621794D03*
X16500Y1669933D03*
Y1677000D03*
Y1683170D03*
Y1689500D03*
Y1696000D03*
Y1702500D03*
Y1712000D03*
Y1717462D03*
Y1665044D03*
X27529Y1719623D03*
Y1672379D03*
Y1675579D03*
Y1684977D03*
Y1688177D03*
Y1697576D03*
Y1700776D03*
X16500Y1749000D03*
Y1756052D03*
Y1765000D03*
Y1774500D03*
Y1784000D03*
Y1790500D03*
Y1724000D03*
Y1730658D03*
Y1736500D03*
Y1743356D03*
X27529Y1722823D03*
Y1735421D03*
Y1732221D03*
Y1748020D03*
Y1744820D03*
Y1760618D03*
Y1757418D03*
X5500Y1880685D03*
Y1888685D03*
X32559Y1986626D03*
X12559D03*
X5500Y1973685D03*
Y1953685D03*
X30200Y1970300D03*
X90018Y5500D03*
X110018D03*
X50018D03*
X70018D03*
X105000Y104788D03*
Y101588D03*
Y85891D03*
Y82691D03*
Y66993D03*
Y63793D03*
X72500Y61161D03*
X105000Y155182D03*
Y151982D03*
X70500Y242988D03*
X97400Y220200D03*
X56024Y292549D03*
X92700Y358400D03*
X105000Y472505D03*
Y469305D03*
X72500Y466673D03*
X105000Y557494D03*
Y510300D03*
Y507100D03*
Y491403D03*
Y488203D03*
X71000Y524464D03*
X105000Y560694D03*
X88600Y623300D03*
X70500Y648500D03*
X48000Y649500D03*
X46500Y653500D03*
X80300Y639977D03*
X50560Y653500D03*
X86900Y774750D03*
X105000Y915812D03*
Y912612D03*
Y896915D03*
Y893715D03*
Y878017D03*
Y874817D03*
X72500Y872185D03*
X105000Y966206D03*
Y963006D03*
X65500Y927500D03*
X41000Y1057500D03*
X88500Y1177300D03*
X105000Y1283529D03*
Y1280329D03*
Y1321324D03*
Y1318124D03*
Y1302427D03*
Y1299227D03*
X58900Y1317000D03*
X105000Y1371718D03*
Y1368518D03*
X80465Y1570120D03*
X109050Y1540600D03*
X46893Y1519979D03*
X47368Y1527323D03*
X42644Y1521957D03*
X43000Y1526000D03*
X42960Y1517408D03*
X105000Y1704739D03*
Y1707939D03*
Y1685841D03*
Y1689041D03*
X72500Y1683209D03*
X51635Y1665355D03*
X105000Y1774030D03*
Y1777230D03*
Y1723636D03*
Y1726836D03*
X67000Y1738000D03*
X71015D03*
X91036Y1835282D03*
X100300Y1830000D03*
X112559Y1986626D03*
X92559D03*
X72559D03*
X52559D03*
X155018Y5500D03*
X170018D03*
X167298Y151203D03*
X154875Y160500D03*
X139095Y214896D03*
Y218096D03*
Y265290D03*
X129000Y255500D03*
X114295Y338300D03*
X139095Y268490D03*
Y284187D03*
Y287387D03*
Y303085D03*
Y306285D03*
X171595Y308917D03*
X173800Y379800D03*
X157200Y412000D03*
X158500Y408000D03*
X125300Y438000D03*
X139095Y620408D03*
Y623608D03*
X150850Y574350D03*
X139095Y670802D03*
Y674002D03*
Y689699D03*
Y692899D03*
X117945Y743800D03*
X139095Y708597D03*
Y711797D03*
X171595Y714429D03*
X174500Y960000D03*
X157200Y950800D03*
X155900Y954200D03*
X157000Y957500D03*
X161200Y946100D03*
X161700Y950800D03*
X139095Y1025920D03*
Y1029120D03*
X137500Y1014500D03*
X139095Y1076314D03*
Y1079514D03*
Y1095211D03*
Y1098411D03*
Y1114109D03*
Y1117309D03*
X171595Y1119941D03*
X117900Y1149200D03*
X167301Y1366838D03*
X158875Y1376100D03*
X139095Y1431432D03*
Y1434632D03*
Y1481826D03*
Y1485026D03*
Y1500723D03*
Y1503923D03*
Y1519621D03*
Y1522821D03*
X171595Y1525453D03*
X144400Y1720400D03*
X136500Y1733000D03*
X137000Y1727500D03*
X140825Y1729825D03*
X140300Y1724100D03*
X147200Y1724400D03*
X139095Y1840144D03*
Y1836944D03*
X151452Y1810000D03*
X139095Y1890538D03*
Y1887338D03*
Y1909435D03*
Y1906235D03*
Y1928333D03*
Y1925133D03*
X171595Y1930965D03*
X172559Y1986626D03*
X152559D03*
X132559D03*
X230018Y5500D03*
X250018D03*
X190018D03*
X210018D03*
X214700Y784200D03*
X203299Y1759750D03*
X252559Y1986626D03*
X232559D03*
X212559D03*
X192559D03*
X310018Y5500D03*
X330018D03*
X270018D03*
X290018D03*
X315000Y412000D03*
X321400Y404400D03*
X327500Y377000D03*
X321500Y408500D03*
X312500Y393050D03*
X313200Y427500D03*
X317000D03*
X321500Y425200D03*
Y417000D03*
Y421000D03*
Y847000D03*
X315000Y842000D03*
X321500Y838500D03*
X321400Y834400D03*
X327500Y807000D03*
X312000Y824500D03*
X321500Y855200D03*
Y851000D03*
X317000Y857900D03*
X313200D03*
X294000Y1111500D03*
X321400Y1205900D03*
X321500Y1210000D03*
X327500Y1178500D03*
X312500Y1194000D03*
X321600Y1226600D03*
X313200Y1228800D03*
X317000D03*
X314437Y1213382D03*
X321500Y1222500D03*
Y1218500D03*
X315000Y1712000D03*
X321500Y1721000D03*
X327500Y1677000D03*
X321500Y1717000D03*
Y1708500D03*
X321400Y1704400D03*
X313500Y1692500D03*
X321500Y1725200D03*
X317000Y1727300D03*
X313200D03*
X312559Y1986626D03*
X292559D03*
X272559D03*
X390018Y5500D03*
X350018D03*
X370018D03*
X331500Y389000D03*
X365100Y371200D03*
X364758Y429249D03*
X385607Y451232D03*
X331500Y819000D03*
X358800Y803600D03*
X385196Y779112D03*
X360800Y858500D03*
X343894Y880707D03*
X331500Y1190500D03*
X364300Y1174900D03*
X391900Y1150250D03*
X365200Y1229800D03*
X343822Y1252222D03*
X379395Y1252274D03*
X356174Y1649291D03*
X331500Y1691000D03*
X369100Y1673700D03*
X331500Y1708500D03*
X365700Y1727700D03*
X343668Y1750741D03*
X392559Y1986626D03*
X372559D03*
X352559D03*
X332559D03*
X470018Y5500D03*
X410018D03*
X430018D03*
X450018D03*
X420722Y820627D03*
X420763Y1223185D03*
X420732Y1721757D03*
X472559Y1986626D03*
X452559D03*
X432559D03*
X412559D03*
X530018Y5500D03*
X510018D03*
X490018D03*
X492559Y1986626D03*
X512559D03*
X532559D03*
X590018Y5500D03*
X570018D03*
X550018D03*
X610018D03*
X552559Y1986626D03*
X572559D03*
X592559D03*
X612559D03*
X670018Y5500D03*
X650018D03*
X630018D03*
X690018D03*
X632559Y1986626D03*
X652559D03*
X672559D03*
X692559D03*
X750018Y5500D03*
X730018D03*
X710018D03*
X712559Y1986626D03*
X732559D03*
X752559D03*
X755995Y1968282D03*
X810018Y5500D03*
X790018D03*
X770018D03*
X830018D03*
X772559Y1986626D03*
X792559D03*
X812559D03*
X832559D03*
X890018Y5500D03*
X870018D03*
X850018D03*
X910018D03*
X896547Y150803D03*
X864975Y148875D03*
X876500Y251000D03*
X901441Y244842D03*
X867441Y214896D03*
Y218096D03*
Y265290D03*
Y268490D03*
Y284187D03*
Y287387D03*
Y303085D03*
Y306285D03*
X899941Y308917D03*
X895547Y556315D03*
X865125Y544000D03*
X867441Y620408D03*
Y623608D03*
X888719Y564519D03*
X867441Y670802D03*
Y674002D03*
Y689699D03*
Y692899D03*
X901200Y655100D03*
X867441Y708597D03*
Y711797D03*
X899941Y714429D03*
X895547Y961827D03*
X888719Y970031D03*
X865125Y949600D03*
X867441Y1025920D03*
Y1029120D03*
X901300Y1060700D03*
X867441Y1076314D03*
Y1079514D03*
Y1095211D03*
Y1098411D03*
Y1114109D03*
Y1117309D03*
X899941Y1119941D03*
X865125Y1346488D03*
X895647Y1367338D03*
X887438Y1373374D03*
X867441Y1431432D03*
Y1434632D03*
Y1481826D03*
Y1485026D03*
Y1500723D03*
X901400Y1466100D03*
X867441Y1503923D03*
Y1519621D03*
Y1522821D03*
X899941Y1525453D03*
X896500Y1681000D03*
X895547Y1772850D03*
X888719Y1781054D03*
X865125Y1751800D03*
X902500Y1734000D03*
X867441Y1836944D03*
Y1840144D03*
Y1887338D03*
Y1890538D03*
Y1906235D03*
Y1909435D03*
Y1925133D03*
Y1928333D03*
X899941Y1930965D03*
X901200Y1871600D03*
X852559Y1986626D03*
X872559D03*
X896546Y1986566D03*
X912559Y1986626D03*
X950018Y5500D03*
X930018D03*
X970018D03*
X943500Y1646989D03*
X941000Y1653000D03*
X947000Y1654500D03*
X921900Y1722400D03*
X932559Y1986626D03*
X952559D03*
X972559D03*
X1031902Y43616D03*
Y23616D03*
X1030018Y5500D03*
X1010018D03*
X990018D03*
X1031902Y63616D03*
Y103616D03*
Y83616D03*
Y143616D03*
Y123616D03*
Y163616D03*
Y183616D03*
Y263616D03*
Y223616D03*
Y203616D03*
Y243616D03*
Y303616D03*
Y283616D03*
Y323616D03*
Y403616D03*
Y383616D03*
Y363616D03*
Y343616D03*
Y483616D03*
Y443616D03*
Y423616D03*
Y463616D03*
Y523616D03*
Y503616D03*
Y543616D03*
Y623616D03*
Y603616D03*
Y583616D03*
Y563616D03*
Y683616D03*
Y663616D03*
Y643616D03*
Y763616D03*
Y743616D03*
Y723616D03*
Y703616D03*
Y843616D03*
Y823616D03*
Y803616D03*
Y783616D03*
Y903616D03*
Y883616D03*
Y863616D03*
Y983616D03*
Y963616D03*
Y943616D03*
Y923616D03*
Y1063616D03*
Y1043616D03*
Y1023616D03*
Y1003616D03*
Y1123616D03*
Y1103616D03*
Y1083616D03*
Y1143616D03*
Y1183616D03*
Y1163616D03*
Y1203616D03*
Y1283616D03*
Y1263616D03*
Y1243616D03*
Y1223616D03*
Y1343616D03*
Y1323616D03*
Y1303616D03*
Y1363616D03*
Y1383616D03*
X991602Y1622500D03*
X1031902Y1785969D03*
Y1745969D03*
Y1725969D03*
Y1765969D03*
Y1865969D03*
Y1845969D03*
Y1805969D03*
Y1825969D03*
Y1925969D03*
Y1885969D03*
Y1905969D03*
Y1965969D03*
Y1945969D03*
X992559Y1986626D03*
X1012559D03*
X1031902Y1985969D03*
G54D11*
X25000Y988000D03*
X27825Y995000D03*
X47500Y660500D03*
X45000Y1057000D03*
X77607Y1565391D03*
X163170Y1210999D03*
X206700Y575000D03*
X401500Y395500D03*
Y830000D03*
X402000Y1196500D03*
Y1695000D03*
X808256Y783275D03*
X807756Y1188775D03*
Y1594275D03*
G54D12*
X38800Y1810100D03*
X22100Y1802800D03*
X38317Y1804491D03*
X34900Y1807200D03*
X35100Y1813000D03*
X26500Y1805200D03*
X26600Y1810600D03*
X26300Y1815000D03*
X30800Y1805300D03*
Y1810500D03*
X17500Y1801900D03*
X22000Y1814100D03*
Y1809100D03*
X17500Y1806900D03*
Y1811900D03*
Y1816500D03*
X7600Y1855000D03*
X17500Y1827500D03*
X22600Y1825200D03*
X17500Y1832500D03*
X22500Y1830000D03*
X17500Y1837500D03*
X22500Y1835000D03*
X17500Y1842500D03*
X22500Y1840000D03*
X17500Y1847500D03*
X22500Y1845000D03*
X17500Y1852500D03*
X22500Y1850000D03*
X17500Y1857500D03*
X22500Y1855000D03*
Y1865000D03*
X17500Y1867500D03*
X22500Y1860000D03*
X12500Y1845000D03*
Y1850000D03*
Y1855000D03*
Y1840000D03*
X17500Y1872500D03*
X22500Y1870000D03*
X12500D03*
X935000Y1425000D03*
X984900Y1430400D03*
X953800Y1424900D03*
X945000Y1425000D03*
X935000Y1455000D03*
Y1475000D03*
Y1445000D03*
Y1465000D03*
Y1435000D03*
X945000Y1475000D03*
X955000D03*
X965000D03*
X945000Y1465000D03*
X955000D03*
X965000D03*
X945000Y1455000D03*
X955000D03*
X965000D03*
X945000Y1445000D03*
X955000D03*
X965000D03*
X945000Y1435000D03*
X955000D03*
X965000D03*
Y1495000D03*
X955000D03*
X935000Y1485000D03*
Y1495000D03*
X945000D03*
Y1485000D03*
X955000D03*
X965000D03*
X975000Y1495000D03*
Y1485000D03*
Y1475000D03*
Y1465000D03*
Y1455000D03*
Y1445000D03*
Y1435000D03*
X965000Y1525000D03*
X955000D03*
X945000D03*
Y1516000D03*
X955000D03*
X965000D03*
X935000Y1555000D03*
X945000D03*
X955000D03*
X965000D03*
X935000Y1575000D03*
Y1565000D03*
X945000Y1575000D03*
X955000D03*
X965000D03*
Y1565000D03*
X955000D03*
X945000D03*
X935000Y1545000D03*
Y1535000D03*
Y1525000D03*
Y1516000D03*
X965000Y1545000D03*
X955000D03*
X945000D03*
Y1535000D03*
X955000D03*
X965000D03*
X975000Y1565000D03*
Y1575000D03*
Y1525000D03*
Y1535000D03*
Y1545000D03*
Y1555000D03*
X935000Y1505000D03*
X955000D03*
X945000D03*
X965000D03*
Y1605000D03*
X935000Y1595000D03*
Y1585000D03*
X945000Y1595000D03*
X955000D03*
X965000D03*
Y1585000D03*
X955000D03*
X945000D03*
X975000Y1595000D03*
Y1605000D03*
Y1585000D03*
X990600Y1427100D03*
X995000Y1425000D03*
X1005000D03*
G54D13*
G01X331500Y1708500D02*
Y1736300D01*
X337182Y1741982D01*
X419518D01*
X473500Y1688000D01*
X679400D01*
X736100Y1744700D01*
X852600D01*
X863100Y1755200D01*
X881300D01*
X902500Y1734000D01*
G01X896500Y1681000D02*
X899000Y1678500D01*
X910000D01*
X921900Y1690400D01*
Y1722400D01*
G54D14*
G01X92700Y358400D02*
X112800Y338300D01*
X114295D01*
G01X86900Y774750D02*
X88750D01*
X92800Y770700D01*
Y758000D01*
X107000Y743800D01*
X117945D01*
G01X117900Y1149200D02*
X89800Y1177300D01*
X88500D01*
G01X80465Y1570120D02*
X85600Y1564985D01*
Y1561400D01*
X106400Y1540600D01*
X109050D01*
G01X91036Y1835282D02*
X96318Y1830000D01*
X100300D01*
G01X173800Y379800D02*
X136600Y342600D01*
X124656D01*
X120356Y338300D01*
X114295D01*
G01X157200Y412000D02*
X131200Y438000D01*
X125300D01*
G01X214700Y784200D02*
X178000D01*
X147700Y753900D01*
X123100D01*
X117945Y748745D01*
Y743800D01*
G01X117900Y1149200D02*
Y1140300D01*
X124100Y1134100D01*
X162700D01*
X167900Y1128900D01*
X220300D01*
X237700Y1111500D01*
X294000D01*
G01X876500Y251000D02*
X885500D01*
X891658Y244842D01*
X901441D01*
G54D15*
G01X-90900Y-277455D02*
Y-294955D01*
X-82166D01*
G01X-69033Y-283289D02*
Y-294955D01*
G01Y-278622D02*
X-69470Y-278330D01*
Y-277747D01*
X-69033Y-277455D01*
X-68596Y-277747D01*
Y-278330D01*
X-69033Y-278622D01*
G01X-54590Y-299330D02*
X-53061Y-300497D01*
X-51315Y-300788D01*
X-49787Y-300497D01*
X-48476Y-299039D01*
X-47603Y-296997D01*
Y-283289D01*
G01Y-285622D02*
X-48476Y-284455D01*
X-49787Y-283580D01*
X-51315Y-283289D01*
X-53061Y-283872D01*
X-54153Y-285038D01*
X-55027Y-287080D01*
X-55463Y-289122D01*
X-55245Y-290872D01*
X-54371Y-292914D01*
X-53061Y-294372D01*
X-51315Y-294955D01*
X-50005Y-294663D01*
X-48476Y-293497D01*
X-47603Y-292331D01*
G01X-37745Y-294955D02*
Y-277455D01*
G01Y-285913D02*
X-36653Y-284455D01*
X-35561Y-283580D01*
X-33815Y-283289D01*
X-32505Y-283580D01*
X-30976Y-284747D01*
X-30321Y-286497D01*
Y-294955D01*
G01X-16533Y-277455D02*
Y-294955D01*
G01X-19590Y-283289D02*
X-13476D01*
G01X-2745Y-294955D02*
Y-283289D01*
G01Y-286205D02*
X-1871Y-284747D01*
X-561Y-283580D01*
X1185Y-283289D01*
X2713Y-283580D01*
X4024Y-284747D01*
X4679Y-286788D01*
Y-294955D01*
G01X18467Y-283289D02*
Y-294955D01*
G01Y-278622D02*
X18030Y-278330D01*
Y-277747D01*
X18467Y-277455D01*
X18904Y-277747D01*
Y-278330D01*
X18467Y-278622D01*
G01X32255Y-294955D02*
Y-283289D01*
G01Y-286205D02*
X33129Y-284747D01*
X34439Y-283580D01*
X36185Y-283289D01*
X37713Y-283580D01*
X39024Y-284747D01*
X39679Y-286788D01*
Y-294955D01*
G01X50410Y-299330D02*
X51939Y-300497D01*
X53685Y-300788D01*
X55213Y-300497D01*
X56524Y-299039D01*
X57397Y-296997D01*
Y-283289D01*
G01Y-285622D02*
X56524Y-284455D01*
X55213Y-283580D01*
X53685Y-283289D01*
X51939Y-283872D01*
X50847Y-285038D01*
X49973Y-287080D01*
X49537Y-289122D01*
X49755Y-290872D01*
X50629Y-292914D01*
X51939Y-294372D01*
X53685Y-294955D01*
X54995Y-294663D01*
X56524Y-293497D01*
X57397Y-292331D01*
G01X84100Y-294955D02*
Y-277455D01*
X89340D01*
X91087Y-278330D01*
X92397Y-280372D01*
X92834Y-282705D01*
X92397Y-285038D01*
X91305Y-286788D01*
X89340Y-287664D01*
X84100D01*
G01X101164Y-294955D02*
Y-277455D01*
X105530D01*
X107277Y-278330D01*
X108587Y-279497D01*
X109679Y-281246D01*
X110552Y-283289D01*
X110770Y-286205D01*
X110552Y-289122D01*
X109679Y-291164D01*
X108587Y-292914D01*
X107277Y-294080D01*
X105530Y-294955D01*
X101164D01*
G01X119100D02*
Y-277455D01*
X124340D01*
X126087Y-278330D01*
X127397Y-280372D01*
X127834Y-282705D01*
X127397Y-285038D01*
X126305Y-286788D01*
X124340Y-287664D01*
X119100D01*
G01X142713Y-285622D02*
X143587Y-284747D01*
X144242Y-283289D01*
X144679Y-281246D01*
X144242Y-279497D01*
X143369Y-278330D01*
X141840Y-277455D01*
X135945D01*
Y-294955D01*
X143150D01*
X144679Y-293789D01*
X145552Y-292038D01*
X145989Y-289997D01*
X145552Y-287955D01*
X144242Y-286205D01*
X142713Y-285622D01*
X135945D01*
G01X171600Y-294955D02*
Y-277455D01*
X176840D01*
X178587Y-278330D01*
X179897Y-280372D01*
X180334Y-282705D01*
X179897Y-285038D01*
X178805Y-286788D01*
X176840Y-287664D01*
X171600D01*
G01X188008Y-277455D02*
X193467Y-294955D01*
X198926Y-277455D01*
G01X210967D02*
Y-294955D01*
G01X205945Y-277455D02*
X215989D01*
G01X21540Y-249955D02*
Y-232455D01*
X27217Y-247038D01*
X32894Y-232455D01*
Y-249955D01*
G01X44717D02*
X43407Y-249663D01*
X42097Y-248497D01*
X41223Y-246455D01*
X40787Y-244122D01*
X41223Y-241788D01*
X42097Y-239747D01*
X43407Y-238580D01*
X44717Y-238289D01*
X46027Y-238580D01*
X47337Y-239747D01*
X48210Y-241788D01*
X48429Y-244122D01*
X48210Y-246455D01*
X47337Y-248497D01*
X46027Y-249663D01*
X44717Y-249955D01*
G01X66147Y-232455D02*
Y-249955D01*
G01Y-247331D02*
X65274Y-248789D01*
X63963Y-249663D01*
X62435Y-249955D01*
X60689Y-249372D01*
X59379Y-247914D01*
X58505Y-246164D01*
X58287Y-244122D01*
X58505Y-242080D01*
X59379Y-240330D01*
X60689Y-238872D01*
X62435Y-238289D01*
X63963Y-238580D01*
X65055Y-239164D01*
X66147Y-240330D01*
G01X76442Y-242080D02*
X83429D01*
X82774Y-240038D01*
X81682Y-238872D01*
X80154Y-238289D01*
X78625Y-238580D01*
X77315Y-239455D01*
X76442Y-241497D01*
X76005Y-243247D01*
Y-244997D01*
X76442Y-246747D01*
X77534Y-248497D01*
X78844Y-249663D01*
X80372Y-249955D01*
X81900Y-249372D01*
X83429Y-247622D01*
G01X97217Y-249955D02*
Y-232455D01*
G01X252500Y-249955D02*
Y-232455D01*
X257740D01*
X259487Y-233330D01*
X260797Y-235372D01*
X261234Y-237705D01*
X260797Y-240038D01*
X259705Y-241788D01*
X257740Y-242664D01*
X252500D01*
G01X279170Y-233914D02*
X277860Y-233038D01*
X276332Y-232455D01*
X274585D01*
X272620Y-233330D01*
X271092Y-234788D01*
X270000Y-236539D01*
X269127Y-239455D01*
X268908Y-242080D01*
X269345Y-244705D01*
X270000Y-246455D01*
X271310Y-248205D01*
X272839Y-249372D01*
X274367Y-249955D01*
X275895D01*
X277424Y-249372D01*
X278734Y-248497D01*
X279826Y-247331D01*
G01X293613Y-240622D02*
X294487Y-239747D01*
X295142Y-238289D01*
X295579Y-236246D01*
X295142Y-234497D01*
X294269Y-233330D01*
X292740Y-232455D01*
X286845D01*
Y-249955D01*
X294050D01*
X295579Y-248789D01*
X296452Y-247038D01*
X296889Y-244997D01*
X296452Y-242955D01*
X295142Y-241205D01*
X293613Y-240622D01*
X286845D01*
G01X302817Y-255788D02*
X315917D01*
G01X321845Y-249955D02*
Y-232455D01*
X331889Y-249955D01*
Y-232455D01*
G01X344367Y-249955D02*
X342620Y-249663D01*
X341092Y-248497D01*
X339782Y-246747D01*
X338908Y-244705D01*
X338472Y-242372D01*
Y-240038D01*
X338908Y-237705D01*
X339782Y-235663D01*
X341092Y-233914D01*
X342620Y-232747D01*
X344367Y-232455D01*
X346113Y-232747D01*
X347642Y-233914D01*
X348952Y-235663D01*
X349826Y-237705D01*
X350262Y-240038D01*
Y-242372D01*
X349826Y-244705D01*
X348952Y-246747D01*
X347642Y-248497D01*
X346113Y-249663D01*
X344367Y-249955D01*
G01X265617Y-294955D02*
Y-277455D01*
X262997Y-280955D01*
G01Y-294955D02*
X268237D01*
G01X278314Y-292331D02*
X279623Y-293789D01*
X281152Y-294663D01*
X283117Y-294955D01*
X285082Y-294372D01*
X286610Y-293205D01*
X287702Y-291164D01*
X287920Y-288830D01*
X287484Y-286497D01*
X286392Y-285038D01*
X284863Y-283872D01*
X283335Y-283580D01*
X281807Y-283872D01*
X279842Y-285038D01*
X280497Y-277455D01*
X286392D01*
G01X296469Y-287664D02*
X297997Y-285622D01*
X299307Y-284455D01*
X301054Y-283872D01*
X302582Y-284455D01*
X303674Y-285622D01*
X304547Y-287372D01*
X304765Y-289413D01*
X304547Y-291164D01*
X303674Y-292914D01*
X302363Y-294372D01*
X300835Y-294955D01*
X299089Y-294372D01*
X297560Y-292622D01*
X296687Y-289997D01*
X296469Y-287080D01*
X296905Y-283289D01*
X297560Y-281246D01*
X298652Y-279205D01*
X300180Y-277747D01*
X301709Y-277455D01*
X303237Y-278038D01*
X304329Y-279497D01*
G01X313969Y-287664D02*
X315497Y-285622D01*
X316807Y-284455D01*
X318554Y-283872D01*
X320082Y-284455D01*
X321174Y-285622D01*
X322047Y-287372D01*
X322265Y-289413D01*
X322047Y-291164D01*
X321174Y-292914D01*
X319863Y-294372D01*
X318335Y-294955D01*
X316589Y-294372D01*
X315060Y-292622D01*
X314187Y-289997D01*
X313969Y-287080D01*
X314405Y-283289D01*
X315060Y-281246D01*
X316152Y-279205D01*
X317680Y-277747D01*
X319209Y-277455D01*
X320737Y-278038D01*
X321829Y-279497D01*
G01X331905Y-292914D02*
X333434Y-294372D01*
X335180Y-294955D01*
X336927Y-294372D01*
X338455Y-292622D01*
X339547Y-289997D01*
X339984Y-287372D01*
Y-284164D01*
X339547Y-281539D01*
X338455Y-279205D01*
X337145Y-278038D01*
X335617Y-277455D01*
X333870Y-278038D01*
X332560Y-279205D01*
X331687Y-280955D01*
X331250Y-283289D01*
X331687Y-285330D01*
X332779Y-287372D01*
X334089Y-288539D01*
X335617Y-288830D01*
X337363Y-288247D01*
X338674Y-286788D01*
X339984Y-284164D01*
G01X395208Y-232455D02*
X400667Y-249955D01*
X406126Y-232455D01*
G01X422534Y-249955D02*
X413800D01*
Y-232455D01*
X422534D01*
G01X419040Y-240913D02*
X413800D01*
G01X431300Y-249955D02*
Y-232455D01*
X436759D01*
X438505Y-233330D01*
X439597Y-234497D01*
X440034Y-236830D01*
X439597Y-239164D01*
X438287Y-240622D01*
X436759Y-241497D01*
X431300D01*
G01X436759D02*
X440034Y-249955D01*
G01X453167Y-250538D02*
X452730Y-250247D01*
Y-249663D01*
X453167Y-249372D01*
X453604Y-249663D01*
Y-250247D01*
X453167Y-250538D01*
G01X426917Y-294955D02*
Y-277455D01*
X424297Y-280955D01*
G01Y-294955D02*
X429537D01*
G01X528750Y-232455D02*
Y-249955D01*
X537484D01*
G01X554547D02*
Y-238289D01*
G01Y-240330D02*
X553674Y-239164D01*
X552363Y-238580D01*
X550835Y-238289D01*
X549307Y-238872D01*
X547997Y-240038D01*
X547123Y-241788D01*
X546687Y-244122D01*
X547123Y-246455D01*
X547997Y-248205D01*
X549307Y-249372D01*
X550835Y-249955D01*
X552363Y-249663D01*
X553674Y-248789D01*
X554547Y-247622D01*
G01X563532Y-255205D02*
X564842Y-255788D01*
X566589Y-255205D01*
X567680Y-254039D01*
X568554Y-252580D01*
X569863Y-247914D01*
X572702Y-238289D01*
G01X565715D02*
X569863Y-247914D01*
G01X582342Y-242080D02*
X589329D01*
X588674Y-240038D01*
X587582Y-238872D01*
X586054Y-238289D01*
X584525Y-238580D01*
X583215Y-239455D01*
X582342Y-241497D01*
X581905Y-243247D01*
Y-244997D01*
X582342Y-246747D01*
X583434Y-248497D01*
X584744Y-249663D01*
X586272Y-249955D01*
X587800Y-249372D01*
X589329Y-247622D01*
G01X600060Y-249955D02*
Y-238289D01*
G01Y-240622D02*
X601152Y-239455D01*
X602244Y-238580D01*
X603772Y-238289D01*
X604863Y-238580D01*
X606174Y-239455D01*
G01X581234Y-277455D02*
Y-294955D01*
X572500D01*
G01X563515Y-287664D02*
X561987Y-285622D01*
X560677Y-284455D01*
X558930Y-283872D01*
X557402Y-284455D01*
X556310Y-285622D01*
X555437Y-287372D01*
X555219Y-289413D01*
X555437Y-291164D01*
X556310Y-292914D01*
X557621Y-294372D01*
X559149Y-294955D01*
X560895Y-294372D01*
X562424Y-292622D01*
X563297Y-289997D01*
X563515Y-287080D01*
X563079Y-283289D01*
X562424Y-281246D01*
X561332Y-279205D01*
X559804Y-277747D01*
X558275Y-277455D01*
X556747Y-278038D01*
X555655Y-279497D01*
G01X670864Y-249955D02*
Y-232455D01*
X675230D01*
X676977Y-233330D01*
X678287Y-234497D01*
X679379Y-236246D01*
X680252Y-238289D01*
X680470Y-241205D01*
X680252Y-244122D01*
X679379Y-246164D01*
X678287Y-247914D01*
X676977Y-249080D01*
X675230Y-249955D01*
X670864D01*
G01X689892Y-242080D02*
X696879D01*
X696224Y-240038D01*
X695132Y-238872D01*
X693604Y-238289D01*
X692075Y-238580D01*
X690765Y-239455D01*
X689892Y-241497D01*
X689455Y-243247D01*
Y-244997D01*
X689892Y-246747D01*
X690984Y-248497D01*
X692294Y-249663D01*
X693822Y-249955D01*
X695350Y-249372D01*
X696879Y-247622D01*
G01X707392Y-247914D02*
X708484Y-249080D01*
X710012Y-249955D01*
X711322D01*
X712632Y-249372D01*
X713505Y-248497D01*
X713942Y-247331D01*
X713724Y-245580D01*
X712850Y-244705D01*
X708920Y-242955D01*
X708047Y-240913D01*
X708484Y-239455D01*
X709357Y-238580D01*
X710667Y-238289D01*
X711977Y-238580D01*
X713287Y-239455D01*
G01X728167Y-238289D02*
Y-249955D01*
G01Y-233622D02*
X727730Y-233330D01*
Y-232747D01*
X728167Y-232455D01*
X728604Y-232747D01*
Y-233330D01*
X728167Y-233622D01*
G01X742610Y-254330D02*
X744139Y-255497D01*
X745885Y-255788D01*
X747413Y-255497D01*
X748724Y-254039D01*
X749597Y-251997D01*
Y-238289D01*
G01Y-240622D02*
X748724Y-239455D01*
X747413Y-238580D01*
X745885Y-238289D01*
X744139Y-238872D01*
X743047Y-240038D01*
X742173Y-242080D01*
X741737Y-244122D01*
X741955Y-245872D01*
X742829Y-247914D01*
X744139Y-249372D01*
X745885Y-249955D01*
X747195Y-249663D01*
X748724Y-248497D01*
X749597Y-247331D01*
G01X759455Y-249955D02*
Y-238289D01*
G01Y-241205D02*
X760329Y-239747D01*
X761639Y-238580D01*
X763385Y-238289D01*
X764913Y-238580D01*
X766224Y-239747D01*
X766879Y-241788D01*
Y-249955D01*
G01X777392Y-242080D02*
X784379D01*
X783724Y-240038D01*
X782632Y-238872D01*
X781104Y-238289D01*
X779575Y-238580D01*
X778265Y-239455D01*
X777392Y-241497D01*
X776955Y-243247D01*
Y-244997D01*
X777392Y-246747D01*
X778484Y-248497D01*
X779794Y-249663D01*
X781322Y-249955D01*
X782850Y-249372D01*
X784379Y-247622D01*
G01X795110Y-249955D02*
Y-238289D01*
G01Y-240622D02*
X796202Y-239455D01*
X797294Y-238580D01*
X798822Y-238289D01*
X799913Y-238580D01*
X801224Y-239455D01*
G01X660367Y-277455D02*
X663423Y-294955D01*
X666917Y-277455D01*
X670410Y-294955D01*
X673467Y-277455D01*
G01X680050Y-294955D02*
Y-277455D01*
X685290D01*
X687037Y-278330D01*
X688347Y-280372D01*
X688784Y-282705D01*
X688347Y-285038D01*
X687255Y-286788D01*
X685290Y-287664D01*
X680050D01*
G01X697332Y-294955D02*
Y-277455D01*
G01X706502D02*
Y-294955D01*
G01Y-286205D02*
X697332D01*
G01X716579Y-289122D02*
X722255D01*
G01X732769Y-294955D02*
Y-277455D01*
X741065D01*
G01X738009Y-285913D02*
X732769D01*
G01X750050Y-277455D02*
Y-294955D01*
X758784D01*
G01X771917D02*
X770170Y-294663D01*
X768642Y-293497D01*
X767332Y-291747D01*
X766458Y-289705D01*
X766022Y-287372D01*
Y-285038D01*
X766458Y-282705D01*
X767332Y-280663D01*
X768642Y-278914D01*
X770170Y-277747D01*
X771917Y-277455D01*
X773663Y-277747D01*
X775192Y-278914D01*
X776502Y-280663D01*
X777376Y-282705D01*
X777812Y-285038D01*
Y-287372D01*
X777376Y-289705D01*
X776502Y-291747D01*
X775192Y-293497D01*
X773663Y-294663D01*
X771917Y-294955D01*
G01X785050D02*
Y-277455D01*
X790509D01*
X792255Y-278330D01*
X793347Y-279497D01*
X793784Y-281830D01*
X793347Y-284164D01*
X792037Y-285622D01*
X790509Y-286497D01*
X785050D01*
G01X790509D02*
X793784Y-294955D01*
G01X801458D02*
X806917Y-277455D01*
X812376Y-294955D01*
G01X810410Y-288830D02*
X803423D01*
G01X841867Y-294955D02*
Y-277455D01*
X839247Y-280955D01*
G01Y-294955D02*
X844487D01*
G01X859367D02*
Y-277455D01*
X856747Y-280955D01*
G01Y-294955D02*
X861987D01*
G01X872937Y-295538D02*
X880797Y-277455D01*
G01X894367Y-294955D02*
Y-277455D01*
X891747Y-280955D01*
G01Y-294955D02*
X896987D01*
G01X907719Y-287664D02*
X909247Y-285622D01*
X910557Y-284455D01*
X912304Y-283872D01*
X913832Y-284455D01*
X914924Y-285622D01*
X915797Y-287372D01*
X916015Y-289413D01*
X915797Y-291164D01*
X914924Y-292914D01*
X913613Y-294372D01*
X912085Y-294955D01*
X910339Y-294372D01*
X908810Y-292622D01*
X907937Y-289997D01*
X907719Y-287080D01*
X908155Y-283289D01*
X908810Y-281246D01*
X909902Y-279205D01*
X911430Y-277747D01*
X912959Y-277455D01*
X914487Y-278038D01*
X915579Y-279497D01*
G01X925437Y-295538D02*
X933297Y-277455D01*
G01X942719Y-280372D02*
X944029Y-278622D01*
X945557Y-277747D01*
X947304Y-277455D01*
X949487Y-278038D01*
X951015Y-279497D01*
X951452Y-281246D01*
X951234Y-282997D01*
X950360Y-284455D01*
X945994Y-287372D01*
X944029Y-289413D01*
X942719Y-292331D01*
X942282Y-294955D01*
X951452D01*
G01X964367Y-277455D02*
X962620Y-278038D01*
X961310Y-279497D01*
X960437Y-281246D01*
X959782Y-283580D01*
X959564Y-286205D01*
X959782Y-288830D01*
X960437Y-291164D01*
X961310Y-292914D01*
X962620Y-294372D01*
X964367Y-294955D01*
X966113Y-294372D01*
X967424Y-292914D01*
X968297Y-291164D01*
X968952Y-288830D01*
X969170Y-286205D01*
X968952Y-283580D01*
X968297Y-281246D01*
X967424Y-279497D01*
X966113Y-278038D01*
X964367Y-277455D01*
G01X981867Y-294955D02*
Y-277455D01*
X979247Y-280955D01*
G01Y-294955D02*
X984487D01*
G01X995219Y-287664D02*
X996747Y-285622D01*
X998057Y-284455D01*
X999804Y-283872D01*
X1001332Y-284455D01*
X1002424Y-285622D01*
X1003297Y-287372D01*
X1003515Y-289413D01*
X1003297Y-291164D01*
X1002424Y-292914D01*
X1001113Y-294372D01*
X999585Y-294955D01*
X997839Y-294372D01*
X996310Y-292622D01*
X995437Y-289997D01*
X995219Y-287080D01*
X995655Y-283289D01*
X996310Y-281246D01*
X997402Y-279205D01*
X998930Y-277747D01*
X1000459Y-277455D01*
X1001987Y-278038D01*
X1003079Y-279497D01*
G01X889564Y-249955D02*
Y-232455D01*
X893930D01*
X895677Y-233330D01*
X896987Y-234497D01*
X898079Y-236246D01*
X898952Y-238289D01*
X899170Y-241205D01*
X898952Y-244122D01*
X898079Y-246164D01*
X896987Y-247914D01*
X895677Y-249080D01*
X893930Y-249955D01*
X889564D01*
G01X915797D02*
Y-238289D01*
G01Y-240330D02*
X914924Y-239164D01*
X913613Y-238580D01*
X912085Y-238289D01*
X910557Y-238872D01*
X909247Y-240038D01*
X908373Y-241788D01*
X907937Y-244122D01*
X908373Y-246455D01*
X909247Y-248205D01*
X910557Y-249372D01*
X912085Y-249955D01*
X913613Y-249663D01*
X914924Y-248789D01*
X915797Y-247622D01*
G01X929367Y-232455D02*
Y-249955D01*
G01X926310Y-238289D02*
X932424D01*
G01X943592Y-242080D02*
X950579D01*
X949924Y-240038D01*
X948832Y-238872D01*
X947304Y-238289D01*
X945775Y-238580D01*
X944465Y-239455D01*
X943592Y-241497D01*
X943155Y-243247D01*
Y-244997D01*
X943592Y-246747D01*
X944684Y-248497D01*
X945994Y-249663D01*
X947522Y-249955D01*
X949050Y-249372D01*
X950579Y-247622D01*
G01X25000Y988000D02*
X8000Y1005000D01*
Y1044500D01*
X23291Y1059791D01*
Y1062791D01*
G01X30000Y991000D02*
Y997000D01*
X13000Y1014000D01*
Y1043500D01*
X23500Y1054000D01*
X42000D01*
X45000Y1057000D01*
G01X27825Y995000D02*
X10500Y1012325D01*
Y1044000D01*
X24000Y1057500D01*
X41000D01*
G01X943500Y1646989D02*
X931900Y1635389D01*
Y1343930D01*
X870100Y1282130D01*
Y1192630D01*
X829870Y1152400D01*
X290630D01*
X254130Y1188900D01*
X227630D01*
X172630Y1243900D01*
X101130D01*
X74400Y1270630D01*
Y1278485D01*
X44451Y1308434D01*
X36170D01*
G01X163170Y1210999D02*
Y1221230D01*
X148400Y1236000D01*
X100120D01*
X37920Y1298200D01*
X30300D01*
X26500Y1302000D01*
Y1305121D01*
G01X33938Y1311000D02*
X36438Y1313500D01*
X45325D01*
X78600Y1280225D01*
Y1272370D01*
X102870Y1248100D01*
X174370D01*
X229370Y1193100D01*
X255870D01*
X291970Y1157000D01*
X385700D01*
X389200Y1160500D01*
X392800D01*
X396300Y1157000D01*
X804250D01*
X809756Y1162506D01*
Y1186775D01*
X807756Y1188775D01*
G01X947000Y1654500D02*
X929800Y1637300D01*
Y1344800D01*
X868000Y1283000D01*
Y1193500D01*
X829000Y1154500D01*
X291500D01*
X255000Y1191000D01*
X228500D01*
X173500Y1246000D01*
X102000D01*
X76500Y1271500D01*
Y1279355D01*
X44855Y1311000D01*
X38500D01*
G01X30000Y1305000D02*
X30766Y1304234D01*
X34856D01*
X100590Y1238500D01*
X172030D01*
X226130Y1184400D01*
X252690D01*
X286430Y1150660D01*
Y1150659D01*
X288889Y1148200D01*
X370580D01*
X375980Y1142800D01*
X856700D01*
X863000Y1136500D01*
X876000D01*
X880200Y1132300D01*
Y1009500D01*
X877300Y1006600D01*
Y981450D01*
X888719Y970031D01*
G01X30700Y1308600D02*
X32034D01*
X34300Y1306334D01*
X35726D01*
X100260Y1241800D01*
X171760D01*
X226760Y1186800D01*
X253260D01*
X289760Y1150300D01*
X377000D01*
X378800Y1148500D01*
X390150D01*
X391900Y1150250D01*
G01X77607Y1565391D02*
Y1564107D01*
X39779Y1526279D01*
Y1465705D01*
X28000Y1453926D01*
Y1444000D01*
G01X30200Y1970300D02*
X31225Y1969275D01*
X130025D01*
X134900Y1964400D01*
X149300D01*
X159000Y1954700D01*
Y1823000D01*
X151452Y1815452D01*
Y1810000D01*
G01X70500Y242988D02*
Y236500D01*
X64000Y230000D01*
Y69661D01*
X72500Y61161D01*
G01X56024Y292549D02*
Y291176D01*
X97400Y249800D01*
Y220200D01*
G01X158500Y408000D02*
X149000D01*
X143500Y402500D01*
X94000D01*
X90500Y406000D01*
Y438500D01*
X69000Y460000D01*
Y468900D01*
X88400Y488300D01*
Y597460D01*
X74651Y611209D01*
Y626449D01*
X47600Y653500D01*
X46500D01*
G01X70500Y648500D02*
Y634000D01*
X76751Y627749D01*
Y612079D01*
X90500Y598330D01*
Y484673D01*
X72500Y466673D01*
G01X71000Y524464D02*
X76900Y530364D01*
Y572700D01*
X64700Y584900D01*
Y633430D01*
X48630Y649500D01*
X48000D01*
G01X88600Y623300D02*
X75000Y636900D01*
Y652607D01*
X74107Y653500D01*
X50560D01*
G01X80300Y639977D02*
X78288Y641989D01*
Y652289D01*
X74477Y656100D01*
X57000D01*
X52600Y660500D01*
X47500D01*
G01X65500Y927500D02*
Y879185D01*
X72500Y872185D01*
G01X58900Y1317000D02*
Y1303500D01*
X80700Y1281700D01*
Y1273240D01*
X91640Y1262300D01*
X212900D01*
X227400Y1247800D01*
X339400D01*
X343822Y1252222D01*
G01X46893Y1519979D02*
X81909D01*
X89030Y1527100D01*
X125610D01*
X138610Y1540100D01*
X302900D01*
X492200Y1350800D01*
X877400D01*
X877401Y1350799D01*
X879139D01*
X893747Y1365407D01*
Y1369047D01*
X924200Y1399500D01*
Y1498000D01*
X897000Y1525200D01*
Y1541500D01*
X926100Y1570600D01*
Y1638100D01*
X941000Y1653000D01*
G01X901400Y1466100D02*
X883000Y1447700D01*
Y1404000D01*
X889539Y1397461D01*
Y1367139D01*
X877400Y1355000D01*
X493970D01*
X301267Y1547703D01*
X140273D01*
X123870Y1531300D01*
X86740D01*
X82763Y1527323D01*
X47368D01*
G01X807756Y1594275D02*
X874225D01*
X881500Y1587000D01*
Y1537500D01*
X915100Y1503900D01*
Y1395000D01*
X891647Y1371547D01*
Y1366277D01*
X878270Y1352900D01*
X493100D01*
X303500Y1542500D01*
X138040D01*
X124740Y1529200D01*
X88160D01*
X83460Y1524500D01*
X45187D01*
X42644Y1521957D01*
G01X887438Y1373374D02*
X886487Y1372423D01*
Y1369149D01*
X874538Y1357200D01*
X494740D01*
X302137Y1549803D01*
X139403D01*
X123000Y1533400D01*
X85870D01*
X82570Y1530100D01*
X46570D01*
X43000Y1526530D01*
Y1526000D01*
G01X420763Y1223185D02*
X414300Y1229648D01*
Y1422000D01*
X298300Y1538000D01*
X139480D01*
X126480Y1525000D01*
X89900D01*
X82308Y1517408D01*
X42960D01*
G01X67000Y1738000D02*
X69500Y1735500D01*
Y1686209D01*
X72500Y1683209D01*
G01X51635Y1665355D02*
X63760Y1677480D01*
X72980D01*
X79000Y1683500D01*
Y1730015D01*
X71015Y1738000D01*
G01X167298Y151203D02*
X196403D01*
X208000Y162800D01*
Y278000D01*
X177083Y308917D01*
X171595D01*
G01X129000Y255500D02*
X134900Y249600D01*
Y228300D01*
X142900Y220300D01*
Y172475D01*
X154875Y160500D01*
G01X150850Y574350D02*
X157300Y567900D01*
Y554600D01*
X173200Y538700D01*
Y533900D01*
X237250Y469850D01*
X355750D01*
X372590Y453010D01*
X383829D01*
X385607Y451232D01*
G01X171595Y714429D02*
X208000Y678024D01*
Y576300D01*
X206700Y575000D01*
G01X174500Y960000D02*
X205600Y991100D01*
Y1085936D01*
X171595Y1119941D01*
G01X137500Y1014500D02*
X157000Y995000D01*
Y974000D01*
X174900Y956100D01*
X185700D01*
X198400Y943400D01*
X879600D01*
X892800Y956600D01*
Y973957D01*
X884400Y982357D01*
Y1043800D01*
X901300Y1060700D01*
G01X157200Y950800D02*
X159400Y953000D01*
X168940D01*
X225940Y896000D01*
X389000D01*
X430300Y854700D01*
Y816200D01*
X442200Y804300D01*
X540840D01*
X568040Y831500D01*
X785500D01*
X805983Y811017D01*
Y781017D01*
X825000Y762000D01*
X856030D01*
X886000Y732030D01*
Y670300D01*
X901200Y655100D01*
G01X808256Y783275D02*
X809756Y784775D01*
Y810244D01*
X786400Y833600D01*
X568910D01*
X568909Y833601D01*
X567171D01*
X539970Y806400D01*
X443130D01*
X432400Y817130D01*
Y855570D01*
X389870Y898100D01*
X226810D01*
X169810Y955100D01*
X156800D01*
X155900Y954200D01*
G01X157000Y957500D02*
X170380D01*
X227680Y900200D01*
X390740D01*
X434500Y856440D01*
Y818000D01*
X444000Y808500D01*
X539100D01*
X566600Y836000D01*
X787000D01*
X891500Y731500D01*
Y688500D01*
X912000Y668000D01*
Y584115D01*
X892404Y564519D01*
X888719D01*
G01X343894Y880707D02*
X337593D01*
X326500Y891800D01*
X224200D01*
X167300Y948700D01*
X163800D01*
X161200Y946100D01*
G01X420722Y820627D02*
X414200Y827149D01*
Y862300D01*
X382600Y893900D01*
X225070D01*
X168170Y950800D01*
X161700D01*
G01X379395Y1252274D02*
X376863Y1254806D01*
X341671D01*
X336765Y1249900D01*
X232300D01*
X205300Y1276900D01*
Y1322200D01*
X158875Y1368625D01*
Y1376100D01*
G01X167301Y1366838D02*
X190938D01*
X208000Y1383900D01*
Y1489048D01*
X171595Y1525453D01*
G01X420732Y1721757D02*
X412600Y1713625D01*
Y1684300D01*
X392600Y1664300D01*
X379600D01*
X376300Y1661000D01*
X326900D01*
X317300Y1670600D01*
X306300D01*
X268500Y1708400D01*
X245800D01*
X238300Y1715900D01*
X148900D01*
X144400Y1720400D01*
G01X356174Y1649291D02*
X346565Y1658900D01*
X326030D01*
X316430Y1668500D01*
X305430D01*
X267630Y1706300D01*
X244930D01*
X237430Y1713800D01*
X145800D01*
X140300Y1719300D01*
Y1724100D01*
G01X343668Y1750741D02*
X338706D01*
X332265Y1744300D01*
X313157D01*
X302557Y1733700D01*
X267300D01*
X257100Y1723500D01*
X213600D01*
X208100Y1718000D01*
X154030D01*
X147630Y1724400D01*
X147200D01*
G01X901200Y1871600D02*
X880516Y1850916D01*
Y1782456D01*
X849960Y1751900D01*
X733460D01*
X677760Y1696200D01*
X476740D01*
X420240Y1752700D01*
X365697D01*
X358352Y1760045D01*
X337699D01*
X330354Y1752700D01*
X310341D01*
X297741Y1740100D01*
X264790D01*
X254490Y1729800D01*
X210989D01*
X209189Y1728000D01*
X152940D01*
X147940Y1733000D01*
X136500D01*
G01X137000Y1727500D02*
X147500D01*
X151200Y1723800D01*
X210930D01*
X212730Y1725600D01*
X256230D01*
X266530Y1735900D01*
X300895D01*
X313495Y1748500D01*
X332110D01*
X337210Y1753600D01*
X358857D01*
X363957Y1748500D01*
X418500D01*
X475000Y1692000D01*
X679500D01*
X735200Y1747700D01*
X851700D01*
X862265Y1758265D01*
X876235D01*
X912200Y1794230D01*
Y1914800D01*
X893100Y1933900D01*
Y1949000D01*
X877300Y1964800D01*
X861400D01*
X856925Y1969275D01*
X756988D01*
X755995Y1968282D01*
G01X888719Y1781054D02*
X886365Y1778700D01*
X879730D01*
X850830Y1749800D01*
X734330D01*
X678630Y1694100D01*
X475870D01*
X419370Y1750600D01*
X364827D01*
X357594Y1757833D01*
X338457D01*
X331224Y1750600D01*
X312050D01*
X299450Y1738000D01*
X265660D01*
X255360Y1727700D01*
X211859D01*
X210059Y1725900D01*
X152070D01*
X148370Y1729600D01*
X141050D01*
X140825Y1729825D01*
G01X203299Y1759750D02*
X205300Y1761751D01*
Y1782400D01*
X208000Y1785100D01*
Y1886700D01*
X171595Y1923105D01*
Y1930965D01*
G01X385196Y779112D02*
X385562D01*
X401750Y795300D01*
X543000D01*
X563600Y815900D01*
X752600D01*
X818700Y749800D01*
X854688D01*
X880400Y724088D01*
Y612200D01*
X863025Y594825D01*
Y525275D01*
X906004Y482296D01*
Y339804D01*
X898041Y331841D01*
Y306459D01*
X923746Y280754D01*
Y194549D01*
X878072Y148875D01*
X864975D01*
G01X865125Y949600D02*
X882830D01*
X890700Y957470D01*
Y973087D01*
X882300Y981487D01*
Y1139000D01*
X869500Y1151800D01*
X832240D01*
X830740Y1150300D01*
X391950D01*
X391900Y1150250D01*
G01X865125Y544000D02*
Y593955D01*
X882500Y611330D01*
Y725000D01*
X855600Y751900D01*
X819570D01*
X742370Y829100D01*
X573830D01*
X542130Y797400D01*
X437075D01*
X422976Y811499D01*
Y818373D01*
X420722Y820627D01*
G01X865125Y1346488D02*
X492412D01*
X477100Y1331176D01*
Y1249000D01*
X447850Y1219750D01*
X424198D01*
X420763Y1223185D01*
G01X420732Y1721757D02*
X422664D01*
X424754Y1719667D01*
X438580D01*
X472547Y1685700D01*
X680600D01*
X737300Y1742400D01*
X855725D01*
X865125Y1751800D01*
G01X896547Y150803D02*
Y164048D01*
X925846Y193347D01*
Y283012D01*
X899941Y308917D01*
G01Y714429D02*
X924300Y690070D01*
Y590301D01*
X895547Y561548D01*
Y556315D01*
G01X899941Y1119941D02*
X911646Y1108236D01*
Y977926D01*
X895547Y961827D01*
G01X895647Y1367338D02*
X926300Y1397991D01*
Y1499094D01*
X899941Y1525453D01*
G01Y1930965D02*
X914400Y1916506D01*
Y1791703D01*
X895547Y1772850D01*
G54D16*
G01X27529Y601522D02*
X28429Y602422D01*
X28865D01*
X32537Y601774D01*
X36423Y599053D01*
X39412Y594782D01*
X40433Y588989D01*
X39833Y588131D01*
X40171Y586211D01*
X41028Y585611D01*
X41367Y583690D01*
X40766Y582833D01*
X41105Y580913D01*
X41962Y580312D01*
X41961D01*
X43791Y569934D01*
X43190Y569077D01*
X43529Y567157D01*
X44386Y566556D01*
X44725Y564636D01*
X44124Y563778D01*
X44463Y561858D01*
X45320Y561258D01*
X45659Y559338D01*
X45058Y558480D01*
X45397Y556560D01*
X46254Y555960D01*
X48236Y544721D01*
X27123Y424955D01*
X26266Y424355D01*
X25927Y422435D01*
X26528Y421577D01*
X26189Y419657D01*
X25332Y419057D01*
X24993Y417137D01*
X25594Y416280D01*
X24767Y411590D01*
X36509Y345005D01*
X100758Y253246D01*
X105143Y228377D01*
X116947Y161440D01*
G02Y161092I-985J-174D01*
G01X116946Y161091D01*
X116436Y158195D01*
X115299Y156572D01*
X112561Y154655D01*
X110441Y154281D01*
X105901D01*
X105000Y155182D01*
G01X27529Y604722D02*
X28429Y603822D01*
X28988D01*
X30944Y603477D01*
X33086Y603099D01*
X37429Y600059D01*
X40737Y595331D01*
X49658Y544721D01*
X26189Y411590D01*
X37834Y345554D01*
X102083Y253795D01*
X106522Y228620D01*
X118326Y161682D01*
G02Y160848I-2364J-417D01*
G01X118325D01*
X117761Y157646D01*
X116305Y155566D01*
X113110Y153330D01*
X110564Y152881D01*
X105899D01*
X105000Y151982D01*
G01Y104788D02*
X105900Y103888D01*
X110441D01*
X116421Y104942D01*
X117344Y105589D01*
X118812Y107685D01*
X118631Y108716D01*
X119750Y110313D01*
X120780Y110494D01*
X121899Y112091D01*
X121718Y113122D01*
X122837Y114719D01*
X123867Y114901D01*
X124986Y116498D01*
X124805Y117528D01*
X125924Y119125D01*
X126954Y119307D01*
X128073Y120904D01*
X129048Y126435D01*
X106277Y255526D01*
X44989Y343034D01*
X30705Y423982D01*
X53543Y553465D01*
X52453Y559647D01*
X51596Y560247D01*
X51257Y562167D01*
X51858Y563025D01*
X51519Y564945D01*
X50662Y565545D01*
X50324Y567465D01*
X50924Y568323D01*
X45456Y599343D01*
X42060Y604191D01*
X41030Y604373D01*
X39911Y605970D01*
X40093Y607001D01*
X38974Y608598D01*
X37944Y608780D01*
X36825Y610377D01*
X37007Y611408D01*
X35888Y613005D01*
X34075Y614275D01*
X30123Y614971D01*
X28429D01*
X27529Y614071D01*
G01X105000Y101588D02*
X105900Y102488D01*
X110564D01*
X116970Y103617D01*
X118350Y104583D01*
X129398Y120355D01*
X130470Y126434D01*
X107602Y256075D01*
X46314Y343583D01*
X32127Y423982D01*
X54965Y553465D01*
X46781Y599892D01*
X36894Y614011D01*
X34624Y615601D01*
X30246Y616371D01*
X28429D01*
X27529Y617271D01*
G01X105000Y85891D02*
X105901Y84990D01*
X110441D01*
X113661Y85558D01*
X117051Y86965D01*
X120987Y89721D01*
X122105Y91318D01*
X121924Y92349D01*
X123042Y93946D01*
X124073Y94128D01*
X125191Y95725D01*
X125010Y96756D01*
X126128Y98353D01*
X127159Y98535D01*
X128277Y100132D01*
X128095Y101163D01*
X129214Y102760D01*
X130245Y102942D01*
X132385Y105999D01*
X135174Y121818D01*
X134835Y123738D01*
X133978Y124339D01*
X133639Y126259D01*
X134239Y127116D01*
X133901Y129037D01*
X133043Y129637D01*
X132705Y131557D01*
X133305Y132414D01*
X111586Y255555D01*
X63761Y323851D01*
X40209Y457417D01*
X57338Y554540D01*
X47007Y613121D01*
X43465Y618179D01*
X39167Y621187D01*
X38137Y621005D01*
X36539Y622123D01*
X36357Y623154D01*
X34760Y624272D01*
X33729Y624090D01*
X32131Y625208D01*
X31950Y626239D01*
X30352Y627357D01*
X28866Y627619D01*
X28429D01*
X27529Y626719D01*
G01X105000Y82691D02*
X105899Y83590D01*
X110564D01*
X114057Y84206D01*
X117729Y85730D01*
X121993Y88715D01*
X133710Y105450D01*
X136596Y121818D01*
X112911Y256104D01*
X65086Y324400D01*
X41631Y457417D01*
X58760Y554540D01*
X48332Y613670D01*
X44471Y619185D01*
X30901Y628682D01*
X28989Y629019D01*
X28429D01*
X27529Y629919D01*
G01Y664515D02*
X28429Y665415D01*
X31134D01*
X37305Y666503D01*
X61986Y662150D01*
X62586Y661293D01*
X64506Y660954D01*
X65364Y661555D01*
X67284Y661216D01*
X67885Y660359D01*
X69805Y660021D01*
X70662Y660621D01*
X80529Y658881D01*
X87500Y654000D01*
X91902Y647714D01*
X92241Y645794D01*
X91641Y644936D01*
X91980Y643016D01*
X92837Y642416D01*
X93176Y640496D01*
X92576Y639638D01*
X92915Y637718D01*
X93772Y637118D01*
X94111Y635198D01*
X93511Y634340D01*
X93850Y632420D01*
X94707Y631820D01*
X94708Y631819D01*
X103999Y579172D01*
X105117Y577575D01*
X104935Y576544D01*
X106054Y574946D01*
X107084Y574765D01*
X108203Y573167D01*
X108021Y572137D01*
X109139Y570539D01*
X110170Y570357D01*
X111741Y568113D01*
X112196Y565533D01*
X111548Y561864D01*
X110731Y560695D01*
X109762Y560016D01*
X108500Y559793D01*
X105901D01*
X105000Y560694D01*
G01Y557494D02*
X105899Y558393D01*
X108623D01*
X110311Y558691D01*
X111736Y559688D01*
X111878Y559890D01*
X111880Y559893D01*
X112874Y561315D01*
X113618Y565533D01*
X113066Y568662D01*
X105324Y579721D01*
X93229Y648260D01*
X88506Y655006D01*
X81078Y660206D01*
X37305Y667925D01*
X31011Y666815D01*
X28429D01*
X27529Y667715D01*
G01X105000Y510300D02*
X105900Y509400D01*
X110441D01*
X111742Y509629D01*
X114036Y511235D01*
X114924Y512503D01*
X116189Y519678D01*
Y523034D01*
X114728Y531317D01*
X115653Y536564D01*
X115053Y537421D01*
X115391Y539341D01*
X116248Y539942D01*
X116587Y541862D01*
X115986Y542719D01*
X116325Y544639D01*
X117182Y545239D01*
X118629Y553446D01*
X115485Y571316D01*
X106893Y583586D01*
X94334Y654774D01*
X94333Y654776D01*
X94335D01*
X94331Y654799D01*
X94329Y654813D01*
X94327Y654822D01*
X90000Y661000D01*
X78098Y669334D01*
X73132Y670209D01*
X72275Y669609D01*
X70355Y669947D01*
X69754Y670805D01*
X67834Y671143D01*
X66977Y670543D01*
X65056Y670881D01*
X64456Y671739D01*
X44760Y675211D01*
X43903Y674611D01*
X41982Y674949D01*
X41382Y675806D01*
X39462Y676145D01*
X38604Y675545D01*
X36684Y675883D01*
X36084Y676740D01*
X34163Y677079D01*
X33306Y676479D01*
X31386Y676817D01*
X30785Y677674D01*
X28865Y678013D01*
X28429D01*
X27529Y677113D01*
G01X105000Y507100D02*
X105900Y508000D01*
X110564D01*
X112291Y508304D01*
X115042Y510229D01*
X116249Y511954D01*
X117600Y519615D01*
X117589Y519617D01*
Y523157D01*
X116150Y531317D01*
X120051Y553446D01*
X116810Y571865D01*
X108218Y584135D01*
X95718Y654991D01*
X95708Y655064D01*
X95634Y655398D01*
X91006Y662006D01*
X78647Y670659D01*
X28988Y679413D01*
X28429D01*
X27529Y680313D01*
G01X105000Y491403D02*
X105901Y490502D01*
X110441D01*
X113751Y491086D01*
X118917Y494703D01*
X120035Y496300D01*
X119854Y497331D01*
X120972Y498928D01*
X122003Y499110D01*
X126129Y505003D01*
X129639Y524907D01*
X121803Y569327D01*
X110482Y585500D01*
X97085Y661453D01*
Y661454D01*
X92466Y668052D01*
X84040Y673951D01*
X83009Y673770D01*
X81412Y674888D01*
X81230Y675919D01*
X79633Y677037D01*
X78602Y676855D01*
X77004Y677973D01*
X76823Y679004D01*
X75225Y680122D01*
X74195Y679941D01*
X72597Y681059D01*
X72415Y682090D01*
X70818Y683208D01*
X44761Y687806D01*
X43904Y687206D01*
X41984Y687545D01*
X41384Y688402D01*
X39463Y688741D01*
X38606Y688141D01*
X36686Y688480D01*
X36085Y689337D01*
X34165Y689676D01*
X33308Y689076D01*
X31387Y689415D01*
X30787Y690272D01*
X28867Y690611D01*
X28429D01*
X27529Y689711D01*
G01X105000Y488203D02*
X105899Y489102D01*
X110564D01*
X114298Y489760D01*
X119923Y493697D01*
X127454Y504454D01*
X131061Y524907D01*
X123128Y569876D01*
X111808Y586048D01*
Y586047D01*
X111785Y586178D01*
X98411Y662002D01*
X93472Y669058D01*
X71367Y684533D01*
X28990Y692011D01*
X28429D01*
X27529Y692911D01*
G01Y702310D02*
X28429Y703210D01*
X28865D01*
X49798Y699521D01*
X50398Y698664D01*
X52318Y698325D01*
X53176Y698925D01*
X55096Y698587D01*
X55697Y697730D01*
X57617Y697392D01*
X58474Y697992D01*
X62430Y697295D01*
X64644Y695745D01*
X64825Y694714D01*
X66423Y693596D01*
X67453Y693778D01*
X69050Y692659D01*
X69232Y691629D01*
X70829Y690510D01*
X71859Y690692D01*
X88258Y679209D01*
X88259D01*
X88441Y678178D01*
X90038Y677060D01*
X91069Y677241D01*
X92666Y676123D01*
X92848Y675092D01*
X94445Y673974D01*
X95476Y674156D01*
X97073Y673037D01*
X99607Y669420D01*
X113291Y591827D01*
X124671Y575566D01*
X136779Y506934D01*
X133983Y491072D01*
X125924Y479561D01*
X122385Y477084D01*
X121355Y477265D01*
X119757Y476147D01*
X119575Y475116D01*
X117978Y473998D01*
X113801Y472264D01*
X110055Y471604D01*
X105901D01*
X105000Y472505D01*
G01X27529Y639318D02*
X28429Y640218D01*
X28866D01*
X34395Y639243D01*
X40519Y634955D01*
X41637Y633358D01*
X41456Y632327D01*
X42574Y630730D01*
X43605Y630548D01*
X49355Y622335D01*
X61373Y554179D01*
X46342Y468824D01*
X72148Y322353D01*
X114490Y261888D01*
X140958Y111807D01*
X139480Y103429D01*
X138623Y102829D01*
X138284Y100909D01*
X138885Y100051D01*
X138546Y98131D01*
X137689Y97531D01*
X137350Y95611D01*
X137951Y94753D01*
X137612Y92833D01*
X136755Y92233D01*
X136417Y90313D01*
X137017Y89456D01*
X136371Y85793D01*
X132115Y79714D01*
X130518Y78596D01*
X129487Y78777D01*
X127890Y77659D01*
X127708Y76628D01*
X126111Y75510D01*
X125080Y75692D01*
X123483Y74573D01*
X123301Y73542D01*
X121703Y72424D01*
X120673Y72606D01*
X119075Y71487D01*
X118894Y70457D01*
X113537Y66706D01*
X110055Y66092D01*
X105901D01*
X105000Y66993D01*
G01Y63793D02*
X105899Y64692D01*
X110178D01*
X114086Y65381D01*
X133121Y78708D01*
X137696Y85244D01*
X142380Y111807D01*
X115815Y262437D01*
X73473Y322902D01*
X47764Y468824D01*
X62795Y554179D01*
X50681Y622880D01*
X50683D01*
X41525Y635961D01*
X34944Y640568D01*
X28989Y641618D01*
X28429D01*
X27529Y642518D01*
G01Y714708D02*
X28429Y715608D01*
X30123D01*
X59553Y710419D01*
X93657Y686539D01*
X104186Y671502D01*
X117340Y596896D01*
X133914Y573241D01*
X155172Y452607D01*
X163794Y440294D01*
X167726Y417993D01*
X166230Y409517D01*
X164362Y406848D01*
X155647Y400746D01*
X93810Y389842D01*
X87492Y385419D01*
X77423Y371038D01*
X73914Y351150D01*
X77157Y332763D01*
X118933Y273099D01*
X128086Y221185D01*
X128883Y220047D01*
X130485Y217757D01*
X132717Y216195D01*
X134977Y215797D01*
X138194D01*
X139095Y214896D01*
G01X27529Y717908D02*
X28429Y717008D01*
X30246D01*
X60102Y711744D01*
X94663Y687545D01*
X105511Y672051D01*
X118665Y597445D01*
X135239Y573790D01*
X156497Y453159D01*
X156496Y453158D01*
X165119Y440843D01*
X169148Y417993D01*
X167555Y408968D01*
X165368Y405842D01*
X156196Y399421D01*
X94359Y388517D01*
X88498Y384413D01*
X78748Y370489D01*
X75336Y351150D01*
X78482Y333312D01*
X120258Y273648D01*
X129411Y221735D01*
X131491Y218763D01*
X133266Y217520D01*
X135100Y217197D01*
X138196D01*
X139095Y218096D01*
G01Y265290D02*
X138195Y266190D01*
X133531D01*
X131009Y266635D01*
X125081Y270784D01*
X80458Y334517D01*
X77535Y351091D01*
X80656Y368795D01*
X80993Y369278D01*
X80994D01*
X81002Y369289D01*
X88494Y379988D01*
X98349Y386885D01*
X156829Y397209D01*
X167119Y404417D01*
X169912Y408407D01*
X171595Y417953D01*
X167441Y441517D01*
X158705Y453991D01*
X137388Y574935D01*
X121019Y598310D01*
X107823Y673160D01*
X83468Y707921D01*
X83469D01*
X62700Y722464D01*
X30123Y728207D01*
X28429D01*
X27529Y727307D01*
G01Y730507D02*
X28429Y729607D01*
X30246D01*
X63249Y723789D01*
X84474Y708928D01*
X109148Y673709D01*
X122344Y598859D01*
X138713Y575484D01*
X160030Y454540D01*
X168766Y442066D01*
X173017Y417953D01*
X171237Y407858D01*
X168125Y403411D01*
X157378Y395884D01*
X98898Y385560D01*
X89500Y378982D01*
X82149Y368485D01*
X82141Y368474D01*
X81982Y368247D01*
X78957Y351091D01*
X81783Y335066D01*
X126087Y271790D01*
X131558Y267960D01*
X133654Y267590D01*
X138195D01*
X139095Y268490D01*
G01Y284187D02*
X138194Y285088D01*
X133530D01*
X125283Y286541D01*
X125282D01*
X113407Y294856D01*
X86771Y332895D01*
X82564Y356751D01*
X84585Y368208D01*
X90819Y377112D01*
X99466Y383169D01*
X158375Y393554D01*
X169115Y401073D01*
X173468Y407294D01*
X175460Y418588D01*
X171209Y442699D01*
X162186Y455593D01*
X140816Y576648D01*
X124554Y599874D01*
X111351Y674763D01*
X66025Y739496D01*
X39537Y758043D01*
X30123Y759703D01*
X28429D01*
X27529Y758803D01*
G01Y762003D02*
X28429Y761103D01*
X30246D01*
X40086Y759368D01*
X67031Y740502D01*
X112676Y675312D01*
X125879Y600423D01*
X142141Y577197D01*
X163511Y456142D01*
X172534Y443248D01*
X176882Y418588D01*
X174793Y406745D01*
X170121Y400067D01*
X158924Y392229D01*
X100015Y381844D01*
X91825Y376106D01*
X85910Y367659D01*
X83986Y356751D01*
X88096Y333445D01*
X114413Y295862D01*
X125829Y287868D01*
X125832Y287866D01*
X133653Y286488D01*
X138196D01*
X139095Y287387D01*
G01X27529Y705510D02*
X28429Y704610D01*
X28988D01*
X62979Y698620D01*
X98079Y674043D01*
X100932Y669969D01*
X114616Y592376D01*
X125996Y576115D01*
X138201Y506934D01*
X135308Y490523D01*
X126930Y478555D01*
X118656Y472763D01*
X114198Y470912D01*
X110178Y470204D01*
X105899D01*
X105000Y469305D01*
G01X139095Y303085D02*
X138194Y303986D01*
X133917D01*
X118450Y306712D01*
X109655Y310362D01*
X89242Y339515D01*
X86786Y353449D01*
X89479Y368712D01*
X93692Y374732D01*
X96971Y377027D01*
X156476Y387520D01*
X171934Y398344D01*
X177061Y405670D01*
X180223Y423610D01*
X177242Y440511D01*
X165920Y456685D01*
X144565Y577768D01*
X128121Y601249D01*
X114792Y676837D01*
X57578Y758570D01*
X40607Y770453D01*
X30123Y772301D01*
X28429D01*
X27529Y771401D01*
G01X139095Y306285D02*
X138196Y305386D01*
X134040D01*
X118845Y308064D01*
X110568Y311499D01*
X90567Y340064D01*
X88208Y353449D01*
X90804Y368163D01*
X94698Y373726D01*
X97520Y375702D01*
X157025Y386195D01*
X172940Y397338D01*
X178387Y405122D01*
X181645Y423610D01*
X178567Y441060D01*
X167245Y457234D01*
X145890Y578317D01*
X129446Y601798D01*
X116117Y677386D01*
X58585Y759573D01*
X58581Y759578D01*
X41156Y771778D01*
X30246Y773701D01*
X28429D01*
X27529Y774601D01*
G01Y843642D02*
X28429Y844542D01*
X30123D01*
X33907Y843874D01*
X40692Y839124D01*
X47965Y828739D01*
X50865Y812286D01*
X66276Y790277D01*
X77977Y782085D01*
X89365Y780076D01*
X155899Y791802D01*
X169353Y801223D01*
X176549Y811501D01*
X178764Y824070D01*
X176409Y837433D01*
X124964Y910908D01*
X116205Y960578D01*
X114290Y963314D01*
X112058Y964876D01*
X109623Y965305D01*
X105901D01*
X105000Y966206D01*
G01X27529Y846842D02*
X28429Y845942D01*
X30246D01*
X34457Y845199D01*
X41696Y840132D01*
X43423Y837667D01*
X44453Y837485D01*
X45572Y835888D01*
X45390Y834857D01*
X49290Y829288D01*
X52190Y812835D01*
X67282Y791283D01*
X78526Y783410D01*
X84067Y782433D01*
X84924Y783033D01*
X86844Y782694D01*
X87445Y781837D01*
X89365Y781498D01*
X155350Y793127D01*
X168347Y802229D01*
X175224Y812050D01*
X177342Y824070D01*
X175084Y836884D01*
X123639Y910359D01*
X123229Y912684D01*
X122372Y913285D01*
X122033Y915205D01*
X122633Y916062D01*
X122294Y917982D01*
X121437Y918583D01*
X121098Y920503D01*
X121699Y921360D01*
X119470Y934000D01*
X118613Y934600D01*
X118274Y936521D01*
X118874Y937378D01*
X118535Y939298D01*
X117678Y939899D01*
X117340Y941819D01*
X117940Y942676D01*
X117601Y944596D01*
X116744Y945197D01*
X116405Y947117D01*
X117006Y947974D01*
X114880Y960029D01*
X113284Y962308D01*
X111509Y963551D01*
X109500Y963905D01*
X105899D01*
X105000Y963006D01*
G01X139095Y620408D02*
X138194Y621309D01*
X136042D01*
X132921Y621859D01*
X130504Y623550D01*
X129279Y625302D01*
X127599Y634823D01*
X129103Y643351D01*
X123561Y674789D01*
X45009Y786980D01*
X35957Y793319D01*
X30123Y794348D01*
X28429D01*
X27529Y793448D01*
G01X139095Y623608D02*
X138196Y622709D01*
X136165D01*
X133470Y623184D01*
X131510Y624556D01*
X130604Y625851D01*
X129021Y634823D01*
X130525Y643351D01*
X124886Y675338D01*
X46015Y787986D01*
X46014Y787987D01*
X36506Y794644D01*
X30246Y795748D01*
X28429D01*
X27529Y796648D01*
G01X139095Y670802D02*
X138195Y671702D01*
X133654D01*
X130858Y672195D01*
X129150Y673390D01*
X37279Y804605D01*
X35213Y806051D01*
X30123Y806947D01*
X28429D01*
X27529Y806047D01*
G01Y809247D02*
X28429Y808347D01*
X30246D01*
X35762Y807376D01*
X38285Y805611D01*
X130156Y674396D01*
X131407Y673520D01*
X133777Y673102D01*
X138195D01*
X139095Y674002D01*
G01Y689699D02*
X138194Y690600D01*
X133654D01*
X124566Y692203D01*
X117712Y697002D01*
X41025Y806521D01*
X40172Y811364D01*
X36113Y817161D01*
X33577Y818936D01*
X30123Y819545D01*
X28429D01*
X27529Y818645D01*
G01Y821845D02*
X28429Y820945D01*
X30246D01*
X34126Y820261D01*
X37119Y818167D01*
X41497Y811913D01*
X42350Y807070D01*
X118718Y698008D01*
X125115Y693528D01*
X133777Y692000D01*
X138196D01*
X139095Y692899D01*
G01Y708597D02*
X138194Y709498D01*
X134040D01*
X117366Y712439D01*
X106748Y719875D01*
X93819Y738337D01*
X46636Y805714D01*
X44343Y818727D01*
X37787Y828088D01*
X32624Y831703D01*
X30123Y832144D01*
X28429D01*
X27529Y831244D01*
G01Y834444D02*
X28429Y833544D01*
X30246D01*
X33173Y833028D01*
X38793Y829094D01*
X45668Y819276D01*
X47961Y806263D01*
X94967Y739141D01*
X107754Y720881D01*
X117915Y713764D01*
X134163Y710898D01*
X138196D01*
X139095Y711797D01*
G01X27529Y894236D02*
X28429Y895136D01*
X30246D01*
X33142Y895646D01*
X36223Y897802D01*
X56211Y926348D01*
X62262Y960664D01*
X68332Y970009D01*
X82543Y979238D01*
X96079Y982118D01*
X103283Y980587D01*
X115179Y972869D01*
X119506Y966689D01*
X124609Y937724D01*
X346954Y620180D01*
X804002Y300148D01*
X856149Y219844D01*
X862384Y215797D01*
X866540D01*
X867441Y214896D01*
G01X27529Y897436D02*
X28429Y896536D01*
X30123D01*
X32593Y896971D01*
X33905Y897889D01*
X34007Y897961D01*
X34562Y898349D01*
X34890Y898580D01*
X35218Y898808D01*
X35217D01*
X54886Y926897D01*
X60932Y961188D01*
X67319Y971022D01*
X81998Y980554D01*
X85610Y981323D01*
X96079Y983550D01*
X103828Y981903D01*
X116170Y973895D01*
X120831Y967238D01*
X125934Y938273D01*
X347960Y621186D01*
X805028Y301139D01*
X857162Y220857D01*
X859980Y219027D01*
X862799Y217197D01*
X866542D01*
X867441Y218096D01*
G01X105000Y915812D02*
X105900Y914912D01*
X110884D01*
X120522Y908164D01*
X173425Y832603D01*
X174989Y823740D01*
X173189Y813519D01*
X166257Y803619D01*
X154153Y795145D01*
X94096Y784555D01*
X76391Y787673D01*
X69178Y792721D01*
X54742Y813338D01*
X50319Y838417D01*
X40282Y852751D01*
X40075Y853047D01*
X36845Y855309D01*
X36844D01*
X35611Y856173D01*
X35610D01*
X30123Y857141D01*
X28429D01*
X27529Y856241D01*
G01X105000Y912612D02*
X105900Y913512D01*
X110442D01*
X119516Y907158D01*
X120634Y905561D01*
X120453Y904530D01*
X121571Y902933D01*
X122602Y902751D01*
X123720Y901153D01*
X123538Y900123D01*
X124657Y898525D01*
X125687Y898344D01*
X126806Y896746D01*
X126624Y895716D01*
X127742Y894118D01*
X128773Y893937D01*
X172100Y832054D01*
X173567Y823740D01*
X171864Y814068D01*
X165251Y804625D01*
X153604Y796470D01*
X94096Y785977D01*
X87537Y787132D01*
X86937Y787989D01*
X85016Y788327D01*
X84159Y787727D01*
X82238Y788065D01*
X81638Y788922D01*
X79718Y789260D01*
X78860Y788660D01*
X76940Y788998D01*
X70184Y793727D01*
X62239Y805073D01*
X62421Y806104D01*
X61302Y807701D01*
X60272Y807883D01*
X59153Y809480D01*
X59335Y810511D01*
X58216Y812108D01*
X57186Y812290D01*
X56067Y813887D01*
X51644Y838966D01*
X41081Y854052D01*
X36160Y857498D01*
X30246Y858541D01*
X28429D01*
X27529Y859441D01*
G01Y906834D02*
X28429Y907734D01*
X30246D01*
X33211Y908257D01*
X38314Y911829D01*
X38317Y911832D01*
X47120Y924405D01*
X60504Y1000316D01*
X64461Y1005967D01*
X64462Y1005968D01*
X66673Y1007515D01*
X71625Y1008390D01*
X75064D01*
X79744Y1007569D01*
X79745D01*
X117197Y981346D01*
X122044Y974425D01*
X128336Y938735D01*
X349165Y623470D01*
X858636Y266740D01*
X861754Y266190D01*
X866541D01*
X867441Y265290D01*
G01X27529Y910034D02*
X28429Y909134D01*
X30123D01*
X32662Y909582D01*
X37311Y912838D01*
X45795Y924954D01*
X59179Y1000865D01*
X63384Y1006870D01*
X63559Y1007045D01*
X66124Y1008840D01*
X71502Y1009790D01*
X75186D01*
X80293Y1008895D01*
X118203Y982352D01*
X123369Y974974D01*
X129661Y939284D01*
X350170Y624477D01*
X859185Y268065D01*
X861877Y267590D01*
X866541D01*
X867441Y268490D01*
G01X27529Y868839D02*
X28429Y869739D01*
X30123D01*
X37785Y868388D01*
X39196Y867400D01*
X44733Y863524D01*
X51602Y853710D01*
X57633Y819498D01*
X57642Y819486D01*
Y819483D01*
X73055Y797463D01*
X78765Y793465D01*
X100428Y789645D01*
X101113D01*
X152273Y798688D01*
X162511Y805857D01*
Y805858D01*
X164425Y807197D01*
X169144Y813936D01*
X170891Y823836D01*
X169517Y831625D01*
X137460Y877406D01*
X110883Y896014D01*
X105901D01*
X105000Y896915D01*
G01X27529Y872039D02*
X28429Y871139D01*
X30246D01*
X38336Y869713D01*
X39875Y868635D01*
X45739Y864530D01*
X52927Y854259D01*
X58959Y820046D01*
X74061Y798469D01*
X79314Y794790D01*
X100551Y791045D01*
X100990D01*
X151724Y800013D01*
X154490Y801951D01*
X154672Y802982D01*
X156269Y804100D01*
X157300Y803919D01*
X158897Y805037D01*
X159079Y806068D01*
X160676Y807186D01*
X161707Y807005D01*
X163419Y808203D01*
X167819Y814485D01*
X169469Y823836D01*
X168192Y831076D01*
X145712Y863179D01*
X144681Y863361D01*
X143563Y864958D01*
X143745Y865989D01*
X142626Y867586D01*
X141595Y867768D01*
X140477Y869365D01*
X140659Y870396D01*
X139540Y871993D01*
X138509Y872175D01*
X137391Y873772D01*
X137573Y874803D01*
X136454Y876400D01*
X119255Y888443D01*
X118225Y888261D01*
X116627Y889379D01*
X116446Y890410D01*
X114848Y891528D01*
X113818Y891347D01*
X112220Y892465D01*
X112038Y893496D01*
X110441Y894614D01*
X105899D01*
X105000Y893715D01*
G01Y878017D02*
X105901Y877116D01*
X110507D01*
X116508Y876058D01*
X150414Y852318D01*
X163952Y832984D01*
X165668Y823251D01*
X164526Y816771D01*
X160470Y810977D01*
X146786Y801392D01*
X100550Y793229D01*
X80155Y796827D01*
X76963Y799062D01*
X62989Y819025D01*
X54933Y864752D01*
X49900Y872300D01*
X49376Y872689D01*
X37375Y881108D01*
X37376Y881109D01*
X33749Y881748D01*
X30123Y882387D01*
X28429D01*
X27529Y881487D01*
G01Y884687D02*
X28429Y883787D01*
X30246D01*
X37925Y882434D01*
X50382Y873694D01*
X50397Y873683D01*
X50921Y873283D01*
X51065Y873077D01*
X56261Y865284D01*
X64314Y819574D01*
X77969Y800068D01*
X80704Y798152D01*
X100550Y794651D01*
X146237Y802717D01*
X155057Y808896D01*
X155239Y809927D01*
X156836Y811046D01*
X157867Y810864D01*
X159464Y811983D01*
X163201Y817320D01*
X164246Y823251D01*
X162627Y832435D01*
X158666Y838091D01*
X157635Y838273D01*
X156517Y839870D01*
X156699Y840901D01*
X155580Y842498D01*
X154549Y842680D01*
X153431Y844277D01*
X153613Y845308D01*
X152494Y846905D01*
X151463Y847087D01*
X150345Y848684D01*
X150527Y849715D01*
X149408Y851312D01*
X129695Y865115D01*
X128665Y864933D01*
X127067Y866051D01*
X126886Y867082D01*
X125288Y868200D01*
X124258Y868019D01*
X122660Y869137D01*
X122478Y870168D01*
X120881Y871286D01*
X119850Y871104D01*
X118253Y872223D01*
X118071Y873254D01*
X115959Y874733D01*
X110384Y875716D01*
X105899D01*
X105000Y874817D01*
G01X867441Y620408D02*
X866540Y621309D01*
X861878D01*
X769612Y681222D01*
X320776Y760379D01*
X217525Y832675D01*
X140277Y943043D01*
X133969Y978804D01*
X113319Y1008298D01*
X102694Y1068581D01*
X72472Y1111737D01*
X40257Y1134294D01*
X30123Y1136081D01*
X28429D01*
X27529Y1135181D01*
G01X867441Y623608D02*
X866542Y622709D01*
X862293D01*
X770136Y682552D01*
X321325Y761704D01*
X218531Y833681D01*
X141603Y943590D01*
X135294Y979354D01*
X135116Y979609D01*
Y979608D01*
X114644Y1008847D01*
X104019Y1069130D01*
X73478Y1112743D01*
X40806Y1135619D01*
X30246Y1137481D01*
X28429D01*
X27529Y1138381D01*
G01X867441Y284187D02*
X866540Y285088D01*
X861754D01*
X831517Y290420D01*
X351897Y626259D01*
X131746Y940703D01*
X125590Y975606D01*
X125589D01*
X99929Y1012251D01*
X91142Y1062077D01*
X84793Y1071141D01*
X51412Y1094511D01*
X28865Y1098485D01*
X28429D01*
X27529Y1097585D01*
G01X867441Y287387D02*
X866542Y286488D01*
X861877D01*
X832066Y291745D01*
X352905Y627264D01*
X352904Y627265D01*
X133071Y941253D01*
X126940Y976013D01*
G03X126832Y976273I-640J-113D01*
G01X101254Y1012800D01*
X92467Y1062626D01*
X85799Y1072147D01*
X51961Y1095836D01*
X28988Y1099885D01*
X28429D01*
X27529Y1100785D01*
G01X867441Y303085D02*
X866540Y303986D01*
X862877D01*
X804071Y314391D01*
X354138Y629447D01*
X135656Y941382D01*
X129367Y977038D01*
X103394Y1014128D01*
X94145Y1066582D01*
X79854Y1086991D01*
X51022Y1107179D01*
X28865Y1111084D01*
X28429D01*
X27529Y1110184D01*
G01X867441Y306285D02*
X866542Y305386D01*
X863000D01*
X804620Y315716D01*
X355144Y630453D01*
X136981Y941931D01*
X130692Y977587D01*
X104719Y1014677D01*
X95470Y1067131D01*
X80860Y1087997D01*
X51571Y1108504D01*
X28988Y1112484D01*
X28429D01*
X27529Y1113384D01*
G01X139095Y1025920D02*
X138194Y1026821D01*
X133654D01*
X130222Y1027426D01*
X127931Y1029030D01*
X125157Y1032989D01*
X115862Y1085688D01*
X53640Y1174551D01*
X42764Y1182166D01*
X38797Y1184944D01*
X30123Y1186474D01*
X28429D01*
X27529Y1185574D01*
G01X139095Y1029120D02*
X138196Y1028221D01*
X133777D01*
X130771Y1028751D01*
X128937Y1030036D01*
X126482Y1033538D01*
X117187Y1086237D01*
X54646Y1175557D01*
X43442Y1183401D01*
X39347Y1186269D01*
X30246Y1187874D01*
X28429D01*
X27529Y1188774D01*
G01Y1147779D02*
X28429Y1148679D01*
X30734D01*
X42332Y1151143D01*
X50018Y1149510D01*
X58111Y1143840D01*
X105032Y1076829D01*
X116883Y1009617D01*
X137368Y980364D01*
X143665Y944662D01*
X220274Y835263D01*
X220476Y835122D01*
X220479Y835120D01*
X220637Y835009D01*
X322221Y763880D01*
X801306Y679404D01*
X813385Y671564D01*
X837044Y666534D01*
X858374Y671068D01*
X861359Y671702D01*
X866541D01*
X867441Y670802D01*
G01X27529Y1150979D02*
X28429Y1150079D01*
X30586D01*
X42332Y1152575D01*
X50588Y1150821D01*
X59117Y1144846D01*
X106357Y1077378D01*
X118208Y1010166D01*
X128273Y995793D01*
X138693Y980913D01*
X144990Y945211D01*
X221278Y836270D01*
X221280Y836269D01*
X221284Y836266D01*
X322770Y765205D01*
X801830Y680734D01*
X813930Y672880D01*
X837044Y667966D01*
X861208Y673102D01*
X866541D01*
X867441Y674002D01*
G01X139095Y1076314D02*
X138195Y1077214D01*
X133654D01*
X130775Y1077722D01*
X130774D01*
X124267Y1082280D01*
X51820Y1185712D01*
X33619Y1198457D01*
X30123Y1199073D01*
X28429D01*
X27529Y1198173D01*
G01X139095Y1079514D02*
X138195Y1078614D01*
X133777D01*
X131324Y1079047D01*
X130924Y1079328D01*
X130584Y1079566D01*
X125273Y1083286D01*
X52826Y1186718D01*
X52825Y1186719D01*
X34168Y1199782D01*
X30246Y1200473D01*
X28429D01*
X27529Y1201373D01*
G01Y1160378D02*
X28429Y1161278D01*
X30023D01*
X36175Y1162584D01*
X46217Y1160813D01*
X56074Y1153911D01*
X108455Y1079102D01*
X120395Y1011387D01*
X140845Y982181D01*
X147264Y945754D01*
X222899Y837761D01*
X323224Y767514D01*
X779815Y686999D01*
X834375Y696619D01*
X862688Y690600D01*
X866540D01*
X867441Y689699D01*
G01X27529Y1163578D02*
X28429Y1162678D01*
X29876D01*
X36150Y1164011D01*
X46766Y1162138D01*
X57080Y1154917D01*
X109780Y1079651D01*
X121720Y1011936D01*
X142170Y982730D01*
X148589Y946303D01*
X223905Y838767D01*
X323773Y768839D01*
X779815Y688421D01*
X834400Y698046D01*
X862836Y692000D01*
X866542D01*
X867441Y692899D01*
G01X139095Y1095211D02*
X138194Y1096112D01*
X133654D01*
X125116Y1097618D01*
X114242Y1105231D01*
X44372Y1205015D01*
X36461Y1210554D01*
X30123Y1211671D01*
X28429D01*
X27529Y1210771D01*
G01X139095Y1098411D02*
X138196Y1097512D01*
X133777D01*
X125665Y1098943D01*
X115248Y1106237D01*
X45518Y1205820D01*
X45375Y1206024D01*
X37010Y1211879D01*
X30246Y1213071D01*
X28429D01*
X27529Y1213971D01*
G01Y1172976D02*
X28429Y1173876D01*
X29682D01*
X35235Y1172899D01*
X60441Y1155249D01*
X111857Y1081818D01*
X124090Y1012451D01*
X144455Y983365D01*
X149910Y952449D01*
X228500Y840187D01*
X328312Y770304D01*
X765405Y693233D01*
X857647Y709498D01*
X866540D01*
X867441Y708597D01*
G01X27529Y1176176D02*
X28429Y1175276D01*
X29805D01*
X35784Y1174224D01*
X61447Y1156255D01*
X113182Y1082367D01*
X125415Y1013000D01*
X145780Y983914D01*
X151235Y952998D01*
X229506Y841193D01*
X328861Y771629D01*
X765405Y694655D01*
X857524Y710898D01*
X866542D01*
X867441Y711797D01*
G01Y1025920D02*
X866540Y1026821D01*
X857826D01*
X262827Y1131754D01*
X177145Y1191752D01*
X153929Y1195846D01*
X90849Y1184723D01*
X79338Y1186752D01*
X59164Y1200878D01*
X52630Y1210211D01*
X47442Y1239641D01*
X40106Y1250119D01*
X32687Y1255314D01*
X30123Y1255766D01*
X28429D01*
X27529Y1254866D01*
G01Y1258066D02*
X28429Y1257166D01*
X30246D01*
X33236Y1256639D01*
X41112Y1251125D01*
X48767Y1240190D01*
X53955Y1210760D01*
X60170Y1201884D01*
X79887Y1188077D01*
X90849Y1186145D01*
X153929Y1197268D01*
X177694Y1193077D01*
X263376Y1133079D01*
X857949Y1028221D01*
X866542D01*
X867441Y1029120D01*
G01Y1076314D02*
X866541Y1077214D01*
X862000D01*
X727443Y1053488D01*
X264461Y1135114D01*
X178615Y1195224D01*
X153975Y1199570D01*
X91244Y1188509D01*
X80252Y1190448D01*
X62257Y1203048D01*
X56429Y1211369D01*
X49795Y1248997D01*
X40315Y1262533D01*
X32613Y1267926D01*
X30123Y1268364D01*
X28429D01*
X27529Y1267464D01*
G01X867441Y1079514D02*
X866541Y1078614D01*
X861877D01*
X727443Y1054910D01*
X265010Y1136439D01*
X179164Y1196549D01*
X153975Y1200992D01*
X91244Y1189931D01*
X80800Y1191774D01*
X63263Y1204054D01*
X57754Y1211918D01*
X51120Y1249546D01*
X41322Y1263538D01*
X41320Y1263540D01*
X33162Y1269251D01*
X30246Y1269764D01*
X28429D01*
X27529Y1270664D01*
G01X867441Y1095211D02*
X866540Y1096112D01*
X862000D01*
X684898Y1064884D01*
X684886Y1064882D01*
X265399Y1138830D01*
X180001Y1198620D01*
X153956Y1203213D01*
X91512Y1192205D01*
X81443Y1193980D01*
X64919Y1205550D01*
X60082Y1212457D01*
X51436Y1261436D01*
X42552Y1274125D01*
X42550Y1274128D01*
X42547Y1274130D01*
X33687Y1280335D01*
X30123Y1280963D01*
X28429D01*
X27529Y1280063D01*
G01X867441Y1098411D02*
X866542Y1097512D01*
X861877D01*
X684898Y1066306D01*
X684886Y1066304D01*
X265948Y1140155D01*
X180550Y1199945D01*
X153956Y1204635D01*
X91512Y1193627D01*
X81992Y1195305D01*
X65925Y1206556D01*
X61407Y1213006D01*
X52761Y1261985D01*
X43555Y1275135D01*
X43553Y1275136D01*
X34279Y1281630D01*
X34249Y1281660D01*
X34236D01*
X30246Y1282363D01*
X28429D01*
X27529Y1283263D01*
G01X139095Y1114109D02*
X138194Y1115010D01*
X134040D01*
X123653Y1116841D01*
X99144Y1134001D01*
X38236Y1220985D01*
X34695Y1223465D01*
X30123Y1224270D01*
X28429D01*
X27529Y1223370D01*
G01X139095Y1117309D02*
X138196Y1116410D01*
X134163D01*
X124202Y1118166D01*
X100150Y1135007D01*
X39241Y1221992D01*
X35244Y1224790D01*
X30246Y1225670D01*
X28429D01*
X27529Y1226570D01*
G01X105000Y1371718D02*
X105901Y1370817D01*
X108500D01*
X109501Y1370994D01*
X110869Y1371951D01*
X111551Y1372926D01*
X111876Y1374770D01*
X111537Y1376695D01*
X109076Y1380210D01*
X109074Y1380211D01*
X104917Y1383122D01*
X92169Y1385372D01*
X87132Y1384484D01*
X85006Y1382994D01*
X82097Y1378838D01*
G02X81507Y1378249I-1965J1378D01*
G02X81505Y1378248I-1075J2147D01*
G01X69006Y1369494D01*
X65580Y1364603D01*
X64709Y1359663D01*
X65309Y1358806D01*
X64970Y1356886D01*
X64113Y1356285D01*
X63774Y1354365D01*
X64375Y1353508D01*
X64036Y1351588D01*
X63179Y1350987D01*
X62840Y1349067D01*
X63440Y1348210D01*
X63101Y1346289D01*
X62244Y1345689D01*
X61705Y1342635D01*
X56901Y1335774D01*
X57083Y1334744D01*
X55965Y1333146D01*
X54934Y1332965D01*
X53816Y1331367D01*
X53997Y1330337D01*
X52879Y1328739D01*
X51848Y1328557D01*
X50730Y1326960D01*
X44809Y1322815D01*
X44627Y1321784D01*
X43030Y1320665D01*
X41999Y1320847D01*
X40402Y1319729D01*
X40220Y1318698D01*
X38623Y1317580D01*
X37592Y1317761D01*
X35995Y1316643D01*
X31257Y1315808D01*
X28429D01*
X27529Y1314908D01*
G01X105000Y1368518D02*
X105899Y1369417D01*
X108623D01*
X110050Y1369669D01*
X111875Y1370945D01*
X112874Y1372375D01*
X112877Y1372377D01*
X113298Y1374770D01*
X112862Y1377244D01*
X110080Y1381217D01*
X105466Y1384448D01*
X92169Y1386794D01*
X86583Y1385809D01*
X84000Y1384000D01*
X80948Y1379641D01*
G02X80702Y1379396I-818J575D01*
G01X68000Y1370500D01*
X64255Y1365152D01*
X60380Y1343184D01*
X49724Y1327966D01*
X35446Y1317968D01*
X31134Y1317208D01*
X28429D01*
X27529Y1318108D01*
G01X105000Y1321324D02*
X105900Y1320424D01*
X108777D01*
X110788Y1320779D01*
X111979Y1321614D01*
X112731Y1322689D01*
X113097Y1324762D01*
X112758Y1326682D01*
X111901Y1327283D01*
X111563Y1329203D01*
X112163Y1330060D01*
X110174Y1341342D01*
X110882Y1345357D01*
X110282Y1346214D01*
X110620Y1348134D01*
X111477Y1348735D01*
X111816Y1350655D01*
X111216Y1351512D01*
X111555Y1353432D01*
X112412Y1354033D01*
X112751Y1355953D01*
X112151Y1356811D01*
X112490Y1358731D01*
X113347Y1359331D01*
X116593Y1377734D01*
X116462Y1378475D01*
X114521Y1381243D01*
X104301Y1388399D01*
X94971Y1390044D01*
X86326Y1388518D01*
X82006Y1385494D01*
X79846Y1382409D01*
X63690Y1371099D01*
X60061Y1365916D01*
X60243Y1364886D01*
X59125Y1363288D01*
X58094Y1363107D01*
X56976Y1361509D01*
X57157Y1360479D01*
X56039Y1358881D01*
X55008Y1358699D01*
X53890Y1357102D01*
X54072Y1356071D01*
X52953Y1354474D01*
X51922Y1354292D01*
X50804Y1352695D01*
Y1352694D01*
X48648Y1340467D01*
X48470Y1340212D01*
Y1340213D01*
X47364Y1338633D01*
X43906Y1333694D01*
X39178Y1330384D01*
X36838Y1329412D01*
X31134Y1328407D01*
X28429D01*
X27529Y1327507D01*
G01X105000Y1318124D02*
X105900Y1319024D01*
X108900D01*
X111337Y1319454D01*
X112985Y1320608D01*
X114057Y1322140D01*
X114519Y1324762D01*
X111596Y1341342D01*
X118015Y1377734D01*
X117787Y1379025D01*
X115526Y1382249D01*
X104850Y1389724D01*
X94971Y1391466D01*
X85777Y1389843D01*
X81000Y1386500D01*
X78840Y1383415D01*
X62684Y1372105D01*
X49479Y1353244D01*
X47323Y1341016D01*
X42900Y1334700D01*
X38499Y1331619D01*
X36443Y1330764D01*
X31011Y1329807D01*
X28429D01*
X27529Y1330707D01*
G01X105000Y1302427D02*
X105901Y1301526D01*
X113786D01*
X115515Y1301221D01*
X118204Y1301695D01*
X119191Y1302386D01*
X119721Y1303143D01*
X120847Y1309527D01*
X120246Y1310384D01*
X120585Y1312304D01*
X121442Y1312905D01*
X121781Y1314825D01*
X121442Y1316745D01*
X120585Y1317346D01*
X120246Y1319266D01*
X120847Y1320123D01*
X120508Y1322044D01*
X119651Y1322644D01*
X119312Y1324564D01*
X119912Y1325421D01*
X116899Y1342508D01*
X121725Y1369880D01*
X119781Y1380917D01*
X117823Y1383713D01*
X92648Y1401342D01*
X85510Y1402602D01*
X80576Y1401730D01*
X74120Y1397207D01*
X71420Y1393350D01*
X71602Y1392320D01*
X70484Y1390722D01*
X69453Y1390540D01*
X64688Y1383733D01*
X64003Y1379848D01*
X47305Y1355997D01*
X47487Y1354967D01*
X46369Y1353369D01*
X45338Y1353187D01*
X44220Y1351590D01*
X44401Y1350560D01*
X43283Y1348962D01*
X42252Y1348780D01*
X41134Y1347183D01*
X41315Y1346153D01*
X40197Y1344555D01*
X39166Y1344373D01*
X38048Y1342776D01*
X36537Y1341978D01*
X31012Y1341005D01*
X28429D01*
X27529Y1340105D01*
G01Y1343305D02*
X28429Y1342405D01*
X30889D01*
X36078Y1343319D01*
X37095Y1343856D01*
X62678Y1380397D01*
X63363Y1384282D01*
X73114Y1398213D01*
X80027Y1403055D01*
X85510Y1404024D01*
X93197Y1402667D01*
X118827Y1384721D01*
X121106Y1381466D01*
X123147Y1369880D01*
X118321Y1342508D01*
X123203Y1314825D01*
X121046Y1302594D01*
X120197Y1301380D01*
X118753Y1300370D01*
X115515Y1299799D01*
X113663Y1300126D01*
X105899D01*
X105000Y1299227D01*
G01X27529Y1352704D02*
X28429Y1353604D01*
X31134D01*
X34323Y1354166D01*
X38627Y1357180D01*
X39746Y1358777D01*
X40776Y1358959D01*
X41895Y1360556D01*
X41713Y1361587D01*
X42831Y1363184D01*
X43862Y1363366D01*
X44981Y1364963D01*
X44799Y1365994D01*
X45917Y1367591D01*
X46948Y1367773D01*
X48066Y1369370D01*
X47885Y1370401D01*
X59075Y1386382D01*
X59348Y1386574D01*
X61707Y1399945D01*
X62565Y1400545D01*
X62904Y1402465D01*
X62304Y1403323D01*
X62643Y1405243D01*
X66681Y1411018D01*
X68675Y1412412D01*
X74011Y1413357D01*
X85593Y1411314D01*
X121031Y1386501D01*
X123482Y1382995D01*
X125787Y1369942D01*
X120812Y1341726D01*
X126237Y1310947D01*
X125898Y1309027D01*
X125041Y1308426D01*
X124703Y1306506D01*
X125303Y1305649D01*
X124964Y1303728D01*
X124107Y1303128D01*
X123769Y1301208D01*
X124369Y1300350D01*
X124368D01*
X123350Y1294573D01*
X122232Y1292975D01*
X121201Y1292794D01*
X120083Y1291196D01*
X120265Y1290165D01*
X116176Y1284324D01*
X115002Y1283502D01*
X109800Y1282605D01*
X109728Y1282628D01*
X105901D01*
X105000Y1283529D01*
G01X27529Y1355904D02*
X28429Y1355004D01*
X31011D01*
X33774Y1355491D01*
X37621Y1358186D01*
X58068Y1387387D01*
X58069D01*
X61317Y1405792D01*
X65675Y1412024D01*
X68126Y1413737D01*
X74011Y1414779D01*
X86142Y1412639D01*
X122037Y1387506D01*
X124808Y1383544D01*
X124807Y1383543D01*
X127209Y1369942D01*
X122234Y1341726D01*
X127659Y1310947D01*
X124675Y1294024D01*
X117182Y1283318D01*
X115549Y1282175D01*
X109700Y1281167D01*
X109509Y1281228D01*
X105899D01*
X105000Y1280329D01*
G01X27529Y1292661D02*
X28429Y1293561D01*
X30123D01*
X32324Y1293173D01*
X32325D01*
X34394Y1291724D01*
X42905Y1285762D01*
X46617Y1280462D01*
X53515Y1270611D01*
X63447Y1214285D01*
X67989Y1207798D01*
X82956Y1197320D01*
X90471Y1195994D01*
X153007Y1207018D01*
X181764Y1201946D01*
X266511Y1142607D01*
X642707Y1076275D01*
X862386Y1115010D01*
X866540D01*
X867441Y1114109D01*
G01X27529Y1295861D02*
X28429Y1294961D01*
X30246D01*
X32873Y1294498D01*
X32875D01*
X32916Y1294469D01*
X43911Y1286768D01*
X47764Y1281265D01*
X54840Y1271160D01*
X64772Y1214834D01*
X68995Y1208804D01*
X83505Y1198645D01*
X90471Y1197416D01*
X153007Y1208440D01*
X182313Y1203271D01*
X267060Y1143932D01*
X452900Y1111165D01*
X501919Y1102522D01*
X642706Y1077697D01*
X862263Y1116410D01*
X866542D01*
X867441Y1117309D01*
G01X27529Y1365102D02*
X28429Y1366002D01*
X30246D01*
X33779Y1366625D01*
X36182Y1368308D01*
X36185D01*
X55633Y1396081D01*
X57420Y1406222D01*
X64162Y1415850D01*
X72279Y1421532D01*
X133531Y1432333D01*
X138194D01*
X139095Y1431432D01*
G01Y1434632D02*
X138196Y1433733D01*
X133408D01*
X71730Y1422857D01*
X63156Y1416856D01*
X56095Y1406771D01*
X54308Y1396630D01*
X44744Y1382972D01*
X35180Y1369315D01*
Y1369316D01*
X33238Y1367956D01*
X33230Y1367950D01*
X30123Y1367402D01*
X28429D01*
X27529Y1368302D01*
G01X139095Y1481826D02*
X138195Y1482726D01*
X133530D01*
X133409Y1482747D01*
X133406Y1482748D01*
X120886Y1484977D01*
X99457Y1499982D01*
X89697Y1501704D01*
X81801Y1500311D01*
X72179Y1493574D01*
X67025Y1486212D01*
X51451Y1397866D01*
X41345Y1383432D01*
X35855Y1379588D01*
X30246Y1378600D01*
X28429D01*
X27529Y1377700D01*
G01X139095Y1485026D02*
X138195Y1484126D01*
X133657D01*
X133652Y1484127D01*
X121436Y1486302D01*
X100006Y1501307D01*
X89697Y1503126D01*
X81252Y1501636D01*
X71173Y1494580D01*
X65700Y1486761D01*
X50126Y1398415D01*
X40339Y1384438D01*
X35306Y1380913D01*
X30123Y1380000D01*
X28429D01*
X27529Y1380900D01*
G01Y1390299D02*
X28429Y1391199D01*
X30246D01*
X35290Y1392088D01*
X35291D01*
X41535Y1396460D01*
X49196Y1407403D01*
X63344Y1487531D01*
X69776Y1496715D01*
X80384Y1504145D01*
X89949Y1505831D01*
X123739Y1499876D01*
X133654Y1501624D01*
X138194D01*
X139095Y1500723D01*
G01X27529Y1393499D02*
X28429Y1392599D01*
X30123D01*
X34741Y1393413D01*
X34749Y1393419D01*
X40529Y1397466D01*
X47871Y1407952D01*
X62019Y1488080D01*
X68770Y1497721D01*
X79835Y1505470D01*
X89949Y1507253D01*
X123739Y1501298D01*
X133530Y1503024D01*
X138196D01*
X139095Y1503923D01*
G01X27529Y1402897D02*
X28429Y1403797D01*
X30123D01*
X36171Y1404864D01*
X42791Y1409496D01*
X46682Y1415054D01*
X59668Y1488727D01*
X67472Y1499867D01*
X84490Y1511785D01*
X134040Y1520522D01*
X138194D01*
X139095Y1519621D01*
G01X27529Y1406097D02*
X28429Y1405197D01*
X30000D01*
X35622Y1406189D01*
X41785Y1410502D01*
X45357Y1415603D01*
X58343Y1489276D01*
X66466Y1500873D01*
X83941Y1513110D01*
X133917Y1521922D01*
X138196D01*
X139095Y1522821D01*
G01X867441Y1431432D02*
X866540Y1432333D01*
X861558D01*
X774394Y1493366D01*
G03X773394Y1493780I-1434J-2048D01*
G01X177868Y1598779D01*
G03X177000I-434J-2462D01*
G01X93095Y1583978D01*
X59048Y1560141D01*
X36724Y1528255D01*
X32838Y1525535D01*
X30123Y1525056D01*
X28429D01*
X27529Y1524156D01*
G01X867441Y1434632D02*
X866542Y1433733D01*
X862000D01*
X775197Y1494513D01*
G03X773637Y1495159I-2237J-3195D01*
G01X178111Y1600159D01*
G03X176757I-677J-3841D01*
G01X92546Y1585303D01*
X58042Y1561147D01*
X35718Y1529261D01*
X32289Y1526860D01*
X30000Y1526456D01*
X28429D01*
X27529Y1527356D01*
G01Y1536755D02*
X28429Y1537655D01*
X30123D01*
X33392Y1538231D01*
X36579Y1540462D01*
X48771Y1557872D01*
X90757Y1587273D01*
X177447Y1602553D01*
G02X178315I434J-2462D01*
G01X857707Y1482762D01*
G03X858124Y1482726I414J2364D01*
G01X866541D01*
X867441Y1481826D01*
G01X27529Y1539955D02*
X28429Y1539055D01*
X30000D01*
X32843Y1539556D01*
X35573Y1541468D01*
X47765Y1558878D01*
X90208Y1588598D01*
X177204Y1603932D01*
G02X178559I677J-3841D01*
G01X857952Y1484141D01*
G03X858126Y1484126I173J985D01*
G01X866541D01*
X867441Y1485026D01*
G01X27529Y1549353D02*
X28429Y1550253D01*
X30123D01*
X32149Y1550610D01*
X89897Y1591043D01*
X176752Y1606351D01*
G02X177620I434J-2462D01*
G01X815998Y1493773D01*
G03X817352I677J3841D01*
G01X861877Y1501624D01*
X866540D01*
X867441Y1500723D01*
G01X27529Y1552553D02*
X28429Y1551653D01*
X30000D01*
X31600Y1551935D01*
X89348Y1592368D01*
X176509Y1607731D01*
G02X177863I677J-3841D01*
G01X773695Y1502657D01*
Y1502656D01*
X816241Y1495153D01*
G03X817109I434J2462D01*
G01X861754Y1503024D01*
X866542D01*
X867441Y1503923D01*
G01X27529Y1561952D02*
X28429Y1562852D01*
X30123D01*
X33358Y1563422D01*
X74273Y1592071D01*
X176679Y1610126D01*
G02X177547I434J-2462D01*
G01X772516Y1505167D01*
G03X773870I677J3841D01*
G01X860949Y1520522D01*
X866540D01*
X867441Y1519621D01*
G01X27529Y1565152D02*
X28429Y1564252D01*
X30000D01*
X30291Y1564304D01*
X31403Y1564499D01*
X32809Y1564747D01*
X73724Y1593396D01*
X176436Y1611506D01*
G02X177790I677J-3841D01*
G01X772759Y1506547D01*
G03X773627I434J2462D01*
G01X860826Y1521922D01*
X866542D01*
X867441Y1522821D01*
G01Y1836944D02*
X866540Y1837845D01*
X862516D01*
X809184Y1849184D01*
X164013Y1735351D01*
X155571Y1736841D01*
X136789Y1749989D01*
Y1749988D01*
G02X135830Y1750947I2236J3195D01*
G01X115823Y1779524D01*
X115822D01*
X104744Y1787281D01*
X91556Y1789606D01*
X85476Y1788534D01*
X84000Y1787500D01*
X80018Y1781813D01*
X70860Y1775401D01*
X64074Y1765710D01*
X44083Y1652336D01*
X33055Y1636573D01*
X31223Y1635293D01*
X28429D01*
X27529Y1634393D01*
G01X867441Y1840144D02*
X866542Y1839245D01*
X862664D01*
X809209Y1850611D01*
X164013Y1736773D01*
X156120Y1738166D01*
X137592Y1751136D01*
G02X136978Y1751750I1434J2048D01*
G01X116829Y1780530D01*
X116828D01*
X105293Y1788606D01*
X91556Y1791028D01*
X84927Y1789859D01*
X83934Y1789164D01*
X83341Y1788748D01*
X82995Y1788506D01*
X79012Y1782819D01*
X69854Y1776407D01*
X62749Y1766259D01*
X42757Y1652885D01*
X32051Y1637581D01*
X32050Y1637580D01*
X30782Y1636693D01*
X28429D01*
X27529Y1637593D01*
G01Y1587199D02*
X28429Y1586299D01*
X30000D01*
X50631Y1589938D01*
X59911Y1596436D01*
X163399Y1614679D01*
X168449Y1618215D01*
X175410Y1628158D01*
X176367Y1633582D01*
X171307Y1662281D01*
X171306D01*
G03X171142Y1662681I-985J-170D01*
G01X142941Y1702957D01*
X141910Y1703138D01*
X140791Y1704736D01*
X140973Y1705766D01*
X131006Y1720001D01*
X129975Y1720183D01*
X128856Y1721780D01*
X129038Y1722811D01*
X127920Y1724408D01*
X126889Y1724590D01*
X125771Y1726187D01*
X125952Y1727218D01*
X124834Y1728815D01*
X123803Y1728997D01*
X122685Y1730594D01*
X122866Y1731625D01*
X121748Y1733222D01*
X117801Y1755605D01*
X116944Y1756205D01*
X116606Y1758126D01*
X117206Y1758983D01*
X116867Y1760903D01*
X116010Y1761504D01*
X115671Y1763424D01*
X116272Y1764281D01*
X115933Y1766202D01*
X115076Y1766802D01*
X114737Y1768722D01*
X115338Y1769580D01*
X114999Y1771500D01*
X114904Y1771636D01*
X114176Y1772677D01*
X111620Y1774466D01*
X109000Y1774929D01*
X105899D01*
X105000Y1774030D01*
G01Y1777230D02*
X105901Y1776329D01*
X109123D01*
X112169Y1775791D01*
X115182Y1773682D01*
Y1773683D01*
X116325Y1772049D01*
X123073Y1733771D01*
X172290Y1663485D01*
X172289Y1663484D01*
G02X172686Y1662524I-1967J-1375D01*
G01Y1662525D01*
X177789Y1633582D01*
X176735Y1627609D01*
X169455Y1617209D01*
X163949Y1613354D01*
X60460Y1595111D01*
X51180Y1588613D01*
X30123Y1584899D01*
X28429D01*
X27529Y1583999D01*
G01Y1599797D02*
X28429Y1598897D01*
X30000D01*
X70475Y1606034D01*
X70476D01*
X81998Y1604001D01*
X161819Y1618073D01*
X166000Y1621000D01*
X171978Y1629538D01*
X172705Y1633662D01*
X169276Y1653108D01*
X144699Y1688204D01*
X143668Y1688385D01*
X142550Y1689983D01*
X142731Y1691013D01*
X136995Y1699204D01*
X135965Y1699386D01*
X134846Y1700983D01*
X135028Y1702014D01*
X133909Y1703611D01*
X132879Y1703793D01*
X131760Y1705390D01*
X131942Y1706421D01*
X130823Y1708018D01*
X129792Y1708200D01*
X128674Y1709797D01*
X128856Y1710828D01*
X127737Y1712425D01*
X123662Y1715278D01*
X122631Y1715097D01*
X121034Y1716215D01*
X120852Y1717246D01*
X119255Y1718364D01*
X118224Y1718183D01*
X116627Y1719301D01*
X116445Y1720332D01*
X114848Y1721450D01*
X113817Y1721268D01*
X112220Y1722387D01*
X112038Y1723418D01*
X110441Y1724536D01*
X105900D01*
X105000Y1723636D01*
G01Y1726836D02*
X105900Y1725936D01*
X110883D01*
X128743Y1713431D01*
X170601Y1653657D01*
X174127Y1633662D01*
X173303Y1628989D01*
X167006Y1619994D01*
X162369Y1616748D01*
X81998Y1602579D01*
X70475Y1604612D01*
X30123Y1597497D01*
X28429D01*
X27529Y1596597D01*
G01X105000Y1704739D02*
X105899Y1705638D01*
X110890D01*
G02X111463Y1705457I-1J-1000D01*
G01X130611Y1692050D01*
X130793Y1691019D01*
X132391Y1689901D01*
X133421Y1690082D01*
X135018Y1688964D01*
X135200Y1687933D01*
X136798Y1686815D01*
X137828Y1686996D01*
X143709Y1682879D01*
G02X143954Y1682633I-575J-818D01*
G01X145510Y1680411D01*
X145328Y1679380D01*
X146446Y1677783D01*
X147477Y1677601D01*
X148596Y1676004D01*
X148414Y1674973D01*
X149532Y1673376D01*
X150563Y1673194D01*
X155156Y1666633D01*
X154975Y1665603D01*
X156093Y1664005D01*
X157124Y1663823D01*
X158242Y1662226D01*
X158060Y1661195D01*
X159179Y1659598D01*
X160209Y1659416D01*
X161327Y1657819D01*
X161146Y1656788D01*
X162264Y1655191D01*
X163295Y1655009D01*
X165888Y1651305D01*
Y1651304D01*
X168852Y1634497D01*
X168113Y1630304D01*
X164441Y1625059D01*
X158945Y1621211D01*
X81913Y1607634D01*
X44945Y1614152D01*
X29877Y1611496D01*
X28429D01*
X27529Y1612396D01*
G01Y1609196D02*
X28429Y1610096D01*
X30000D01*
X44945Y1612730D01*
X81913Y1606212D01*
X159495Y1619886D01*
X165447Y1624053D01*
X169438Y1629755D01*
X170274Y1634497D01*
X167213Y1651854D01*
X145101Y1683437D01*
G03X144512Y1684026I-1966J-1377D01*
G01X112266Y1706604D01*
G03X110890Y1707038I-1376J-1966D01*
G01X105901D01*
X105000Y1707939D01*
G01X27529Y1624994D02*
X28429Y1624094D01*
X30123D01*
X40396Y1622283D01*
X47350Y1617414D01*
X82059Y1611287D01*
X151075Y1623457D01*
X158673Y1628777D01*
X158674Y1628779D01*
X161123Y1632275D01*
X161612Y1635048D01*
X159575Y1646603D01*
X158456Y1648200D01*
X157426Y1648382D01*
X156307Y1649979D01*
X156489Y1651010D01*
X151620Y1657962D01*
X150590Y1658144D01*
X149471Y1659741D01*
X149653Y1660772D01*
X148534Y1662369D01*
X147504Y1662551D01*
X146385Y1664148D01*
X146567Y1665179D01*
X145448Y1666776D01*
X144417Y1666958D01*
X143299Y1668555D01*
X143481Y1669586D01*
X142362Y1671183D01*
X137031Y1674917D01*
X136000Y1674735D01*
X134403Y1675854D01*
X134221Y1676884D01*
X132624Y1678003D01*
X131593Y1677821D01*
X129996Y1678940D01*
X129814Y1679970D01*
X128217Y1681089D01*
X127186Y1680907D01*
X125589Y1682026D01*
X125407Y1683056D01*
X123810Y1684175D01*
G03X123413Y1684339I-571J-820D01*
G01Y1684340D01*
X110055Y1686740D01*
X105899D01*
X105000Y1685841D01*
G01X27529Y1621794D02*
X28429Y1622694D01*
X30000D01*
X39846Y1620958D01*
X46801Y1616089D01*
X82059Y1609865D01*
X151624Y1622132D01*
X159680Y1627773D01*
X162448Y1631726D01*
X163034Y1635048D01*
X160900Y1647152D01*
X143368Y1672189D01*
X124613Y1685322D01*
G03X123661Y1685718I-1376J-1967D01*
G01X110180Y1688140D01*
X105901D01*
X105000Y1689041D01*
G01X139095Y1836944D02*
X138194Y1837845D01*
X133408D01*
X107399Y1842430D01*
G03X107085Y1842435I-173J-985D01*
G01X77771Y1837267D01*
X63445Y1827236D01*
X56212Y1816904D01*
X40668Y1728688D01*
X36920Y1723335D01*
X33644Y1721041D01*
X30706Y1720523D01*
X28429D01*
X27529Y1719623D01*
G01Y1672379D02*
X28429Y1673279D01*
X34396D01*
X38372Y1673981D01*
X42093Y1676588D01*
X45119Y1680911D01*
X60825Y1769981D01*
X67484Y1779492D01*
X76008Y1785459D01*
X77789Y1788002D01*
X86525Y1794117D01*
X91963Y1795076D01*
X106818Y1792456D01*
X115465Y1786401D01*
X138599Y1753369D01*
X138601Y1753366D01*
G03X139559Y1752409I3193J2239D01*
G01X155697Y1741110D01*
X164841Y1739497D01*
Y1739496D01*
X792676Y1850261D01*
X845134Y1886991D01*
X851993Y1888200D01*
X866579D01*
X867441Y1887338D01*
G01X27529Y1675579D02*
X28429Y1674679D01*
X34273D01*
X37823Y1675306D01*
X41087Y1677593D01*
X43793Y1681460D01*
X43794Y1681462D01*
X59500Y1770530D01*
X66478Y1780498D01*
X75002Y1786465D01*
X76783Y1789008D01*
X85976Y1795442D01*
X91963Y1796498D01*
X107367Y1793781D01*
X116471Y1787407D01*
X139746Y1754172D01*
X139747D01*
G03X140361Y1753558I2048J1434D01*
G01X156245Y1742436D01*
X164840Y1740919D01*
Y1740920D01*
X164841Y1740919D01*
X792127Y1851586D01*
X844585Y1888316D01*
X851870Y1889600D01*
X866503D01*
X867441Y1890538D01*
G01X27529Y1684977D02*
X28352Y1685800D01*
X30768D01*
X34930Y1686534D01*
X40476Y1690416D01*
X43574Y1694842D01*
X59539Y1785364D01*
X69236Y1799213D01*
X76557Y1804340D01*
X80365Y1807006D01*
X86503Y1808089D01*
X93366Y1806880D01*
G02X93766Y1806714I-174J-985D01*
G01X117295Y1790236D01*
X117298Y1790234D01*
G02X117543Y1789989I-574J-819D01*
G01X141029Y1756459D01*
G03X141986Y1755502I3194J2237D01*
G01X141990Y1755499D01*
X157223Y1744832D01*
X164932Y1743472D01*
X769273Y1849995D01*
X769278D01*
X847122Y1904513D01*
X862000Y1907136D01*
X866540D01*
X867441Y1906235D01*
G01X27529Y1688177D02*
X28506Y1687200D01*
X30645D01*
X34381Y1687859D01*
X39470Y1691422D01*
X42249Y1695391D01*
X58214Y1785913D01*
X58391Y1786167D01*
X58392D01*
X63241Y1793092D01*
X68230Y1800219D01*
X75754Y1805487D01*
X79816Y1808331D01*
X86503Y1809511D01*
X93609Y1808259D01*
G02X94569Y1807861I-417J-2364D01*
G01X106334Y1799622D01*
X118099Y1791384D01*
G02X118688Y1790795I-1377J-1966D01*
G01X118690Y1790792D01*
X142177Y1757263D01*
X142179Y1757260D01*
G03X142793Y1756646I2048J1434D01*
G01Y1756647D01*
X157772Y1746157D01*
X164932Y1744894D01*
X768730Y1851321D01*
X846573Y1905838D01*
X861877Y1908536D01*
X866542D01*
X867441Y1909435D01*
G01Y1925133D02*
X866540Y1926034D01*
X861996D01*
X849915Y1923904D01*
X743401Y1849321D01*
X165003Y1747353D01*
X165000D01*
X158498Y1748500D01*
X144561Y1758260D01*
G02X143604Y1759218I2239J3194D01*
G01X108992Y1808645D01*
X108989Y1808648D01*
X91702Y1820752D01*
X91373Y1820932D01*
X90602Y1821251D01*
X90396Y1821336D01*
X90274Y1821370D01*
X81061Y1822996D01*
G03X80713Y1822997I-177J-984D01*
G01X71088Y1821301D01*
X66921Y1818384D01*
X59859Y1808264D01*
X41846Y1706111D01*
X39400Y1702620D01*
X34267Y1699027D01*
X31141Y1698476D01*
X28429D01*
X27529Y1697576D01*
G01X867441Y1928333D02*
X866542Y1927434D01*
X861873D01*
X849366Y1925229D01*
X742852Y1850646D01*
X165003Y1748775D01*
X159047Y1749825D01*
X145368Y1759405D01*
G02X144754Y1760019I1434J2048D01*
G01X110138Y1809450D01*
X110136Y1809453D01*
Y1809452D01*
X110000Y1809646D01*
Y1809650D01*
X109792Y1809796D01*
Y1809797D01*
X92442Y1821943D01*
X91978Y1822197D01*
X91137Y1822545D01*
X90853Y1822662D01*
X90584Y1822737D01*
X81304Y1824376D01*
G03X80469I-417J-2363D01*
G01X70539Y1822626D01*
X65915Y1819389D01*
X58534Y1808812D01*
X40521Y1706660D01*
X38394Y1703626D01*
X38124Y1703437D01*
X36057Y1701989D01*
X33718Y1700352D01*
X31018Y1699876D01*
X28429D01*
X27529Y1700776D01*
G01X139095Y1840144D02*
X138196Y1839245D01*
X133531D01*
X107648Y1843810D01*
X107492Y1843833D01*
X107381Y1843910D01*
X77222Y1838592D01*
X62439Y1828242D01*
X54887Y1817453D01*
X39343Y1729237D01*
X35916Y1724342D01*
X35914Y1724341D01*
X33095Y1722366D01*
X30583Y1721923D01*
X28429D01*
X27529Y1722823D01*
G01X139095Y1890538D02*
X138195Y1889638D01*
X133654D01*
X112273Y1893408D01*
X96841Y1890750D01*
X71493Y1873004D01*
X57462Y1852964D01*
X37956Y1742344D01*
X33817Y1736434D01*
X31084Y1734521D01*
X28429D01*
X27529Y1735421D01*
G01X139095Y1887338D02*
X138195Y1888238D01*
X133531D01*
X112270Y1891986D01*
X97387Y1889423D01*
X72499Y1871998D01*
X58787Y1852415D01*
X39281Y1741795D01*
X34823Y1735428D01*
X31633Y1733196D01*
X31207Y1733121D01*
X28429D01*
X27529Y1732221D01*
G01X139095Y1909435D02*
X138196Y1908536D01*
X133531D01*
X101457Y1902881D01*
X75179Y1884482D01*
X54014Y1854253D01*
X35854Y1751305D01*
X34295Y1749078D01*
X31638Y1747218D01*
X31083Y1747120D01*
X28429D01*
X27529Y1748020D01*
G01X139095Y1906235D02*
X138194Y1907136D01*
X133654D01*
X102006Y1901556D01*
X76185Y1883476D01*
X55339Y1853704D01*
X37179Y1750756D01*
X35301Y1748072D01*
X32187Y1745893D01*
X31206Y1745720D01*
X28429D01*
X27529Y1744820D01*
G01X139095Y1928333D02*
X138196Y1927434D01*
X133917D01*
X105813Y1922479D01*
X88901Y1910638D01*
X50408Y1855670D01*
X33990Y1762605D01*
X32433Y1760381D01*
X31621Y1759813D01*
X31083Y1759718D01*
X28429D01*
X27529Y1760618D01*
G01X139095Y1925133D02*
X138194Y1926034D01*
X134040D01*
X106362Y1921154D01*
X89907Y1909632D01*
X51733Y1855121D01*
X35315Y1762056D01*
X33439Y1759375D01*
X32168Y1758487D01*
X31595Y1758386D01*
X31209Y1758318D01*
X28429D01*
X27529Y1757418D01*
M02*
